G04 ================== begin FILE IDENTIFICATION RECORD ==================*
G04 Layout Name:  D:/<user>/Wistron_project/16318-2/gbr/16318-2.brd*
G04 Film Name:    DRILL*
G04 File Format:  Gerber RS274X*
G04 File Origin:  Cadence Allegro 16.5-S056*
G04 Origin Date:  Mon Aug 07 11:09:21 2017*
G04 *
G04 Layer:  MANUFACTURING/NCLEGEND-1-8*
G04 Layer:  MANUFACTURING/DRILL SIZE*
G04 Layer:  DRAWING FORMAT/LAYER_PCB_STORY*
G04 Layer:  DRAWING FORMAT/LAYER_DRILL*
G04 Layer:  BOARD GEOMETRY/PANEL_OUTLINE*
G04 *
G04 Offset:    (0.00 0.00)*
G04 Mirror:    No*
G04 Mode:      Positive*
G04 Rotation:  0*
G04 FullContactRelief:  No*
G04 UndefLineWidth:     6.00*
G04 ================== end FILE IDENTIFICATION RECORD ====================*
%FSLAX35Y35*MOIN*%
%IR0*IPPOS*OFA0.00000B0.00000*MIA0B0*SFA1.00000B1.00000*%
%AMMACRO13*
1,1,.006,.005,.005*
20,1,.006,.005,.005,.005,-.005,0.0*
1,1,.006,.005,-.005*
20,1,.006,.005,-.005,-.005,-.005,0.0*
1,1,.006,-.005,-.005*
20,1,.006,-.005,-.005,-.005,.005,0.0*
1,1,.006,-.005,.005*
20,1,.006,-.005,.005,.005,.005,0.0*
1,1,.006,.005,.005*
1,1,.006,-.00158,.00167*
20,1,.006,-.00158,.00167,-.00108,.00217,0.0*
1,1,.006,-.00108,.00217*
20,1,.006,-.00108,.00217,-.0005,.00242,0.0*
1,1,.006,-.0005,.00242*
20,1,.006,-.0005,.00242,.00017,.0025,0.0*
1,1,.006,.00017,.0025*
20,1,.006,.00017,.0025,.001,.00233,0.0*
1,1,.006,.001,.00233*
20,1,.006,.001,.00233,.00158,.00192,0.0*
1,1,.006,.00158,.00192*
20,1,.006,.00158,.00192,.00175,.00142,0.0*
1,1,.006,.00175,.00142*
20,1,.006,.00175,.00142,.00167,.00092,0.0*
1,1,.006,.00167,.00092*
20,1,.006,.00167,.00092,.00133,.0005,0.0*
1,1,.006,.00133,.0005*
20,1,.006,.00133,.0005,-.00033,-.00033,0.0*
1,1,.006,-.00033,-.00033*
20,1,.006,-.00033,-.00033,-.00108,-.00092,0.0*
1,1,.006,-.00108,-.00092*
20,1,.006,-.00108,-.00092,-.00158,-.00175,0.0*
1,1,.006,-.00158,-.00175*
20,1,.006,-.00158,-.00175,-.00175,-.0025,0.0*
1,1,.006,-.00175,-.0025*
20,1,.006,-.00175,-.0025,.00175,-.0025,0.0*
1,1,.006,.00175,-.0025*
%
%ADD13MACRO13*%
%AMMACRO20*
1,1,.006,.004,0.0*
20,1,.006,.004,0.0,-.004,0.0,0.0*
1,1,.006,-.004,0.0*
1,1,.006,0.0,.004*
20,1,.006,0.0,.004,0.0,-.004,0.0*
1,1,.006,0.0,-.004*
1,1,.006,.002,0.0*
20,1,.006,.002,0.0,.002,.004,0.0*
1,1,.006,.002,.004*
20,1,.006,.002,.004,.0012,.0032,0.0*
1,1,.006,.0012,.0032*
1,1,.006,.0012,0.0*
20,1,.006,.0012,0.0,.0028,0.0,0.0*
1,1,.006,.0028,0.0*
%
%ADD20MACRO20*%
%AMMACRO22*
1,1,.006,.01067,-.016*
20,1,.006,.01067,-.016,-.01067,-.016,0.0*
1,1,.006,-.01067,-.016*
20,1,.006,-.01067,-.016,-.01067,.016,0.0*
1,1,.006,-.01067,.016*
20,1,.006,-.01067,.016,.01067,.016,0.0*
1,1,.006,.01067,.016*
1,1,.006,.00213,.00053*
20,1,.006,.00213,.00053,-.01067,.00053,0.0*
1,1,.006,-.01067,.00053*
%
%ADD22MACRO22*%
%AMMACRO18*
1,1,.006,-.04333,.065*
20,1,.006,-.04333,.065,-.04333,-.065,0.0*
1,1,.006,-.04333,-.065*
20,1,.006,-.04333,-.065,.04333,-.065,0.0*
1,1,.006,.04333,-.065*
%
%ADD18MACRO18*%
%AMMACRO28*
1,1,.006,.002935,-.007085*
20,1,.006,.002935,-.007085,-.002935,-.007085,0.0*
1,1,.006,-.002935,-.007085*
20,1,.006,-.002935,-.007085,-.007085,-.002935,0.0*
1,1,.006,-.007085,-.002935*
20,1,.006,-.007085,-.002935,-.007085,.002935,0.0*
1,1,.006,-.007085,.002935*
20,1,.006,-.007085,.002935,-.002935,.007085,0.0*
1,1,.006,-.002935,.007085*
20,1,.006,-.002935,.007085,.002935,.007085,0.0*
1,1,.006,.002935,.007085*
20,1,.006,.002935,.007085,.007085,.002935,0.0*
1,1,.006,.007085,.002935*
20,1,.006,.007085,.002935,.007085,-.002935,0.0*
1,1,.006,.007085,-.002935*
20,1,.006,.007085,-.002935,.002935,-.007085,0.0*
1,1,.006,.002935,-.007085*
1,1,.006,-.0026,-.00248*
20,1,.006,-.0026,-.00248,-.00189,-.00307,0.0*
1,1,.006,-.00189,-.00307*
20,1,.006,-.00189,-.00307,-.00106,-.00342,0.0*
1,1,.006,-.00106,-.00342*
20,1,.006,-.00106,-.00342,0.0,-.00354,0.0*
1,1,.006,0.0,-.00354*
20,1,.006,0.0,-.00354,.00106,-.0033,0.0*
1,1,.006,.00106,-.0033*
20,1,.006,.00106,-.0033,.00189,-.00283,0.0*
1,1,.006,.00189,-.00283*
20,1,.006,.00189,-.00283,.00248,-.00201,0.0*
1,1,.006,.00248,-.00201*
20,1,.006,.00248,-.00201,.0026,-.00106,0.0*
1,1,.006,.0026,-.00106*
20,1,.006,.0026,-.00106,.00236,-.00012,0.0*
1,1,.006,.00236,-.00012*
20,1,.006,.00236,-.00012,.00177,.00047,0.0*
1,1,.006,.00177,.00047*
20,1,.006,.00177,.00047,.00094,.00094,0.0*
1,1,.006,.00094,.00094*
20,1,.006,.00094,.00094,.00012,.00106,0.0*
1,1,.006,.00012,.00106*
20,1,.006,.00012,.00106,-.00071,.00094,0.0*
1,1,.006,-.00071,.00094*
20,1,.006,-.00071,.00094,-.00177,.00047,0.0*
1,1,.006,-.00177,.00047*
20,1,.006,-.00177,.00047,-.00142,.00354,0.0*
1,1,.006,-.00142,.00354*
20,1,.006,-.00142,.00354,.00177,.00354,0.0*
1,1,.006,.00177,.00354*
%
%ADD28MACRO28*%
%AMMACRO26*
1,1,.006,-.01077,-.017*
20,1,.006,-.01077,-.017,-.01077,.017,0.0*
1,1,.006,-.01077,.017*
20,1,.006,-.01077,.017,.01077,.017,0.0*
1,1,.006,.01077,.017*
1,1,.006,.00283,.00057*
20,1,.006,.00283,.00057,-.01077,.00057,0.0*
1,1,.006,-.01077,.00057*
%
%ADD26MACRO26*%
%AMMACRO14*
1,1,.006,.0184,.0046*
20,1,.006,.0184,.0046,.0276,.0115,0.0*
1,1,.006,.0276,.0115*
20,1,.006,.0276,.0115,.0345,.023,0.0*
1,1,.006,.0345,.023*
20,1,.006,.0345,.023,.0391,.0391,0.0*
1,1,.006,.0391,.0391*
20,1,.006,.0391,.0391,.0345,.0529,0.0*
1,1,.006,.0345,.0529*
20,1,.006,.0345,.0529,.0253,.0621,0.0*
1,1,.006,.0253,.0621*
20,1,.006,.0253,.0621,.0092,.069,0.0*
1,1,.006,.0092,.069*
20,1,.006,.0092,.069,-.0529,.069,0.0*
1,1,.006,-.0529,.069*
20,1,.006,-.0529,.069,-.0529,-.069,0.0*
1,1,.006,-.0529,-.069*
20,1,.006,-.0529,-.069,.023,-.069,0.0*
1,1,.006,.023,-.069*
20,1,.006,.023,-.069,.0391,-.0598,0.0*
1,1,.006,.0391,-.0598*
20,1,.006,.0391,-.0598,.0483,-.046,0.0*
1,1,.006,.0483,-.046*
20,1,.006,.0483,-.046,.0529,-.0299,0.0*
1,1,.006,.0529,-.0299*
20,1,.006,.0529,-.0299,.0483,-.0138,0.0*
1,1,.006,.0483,-.0138*
20,1,.006,.0483,-.0138,.0345,0.0,0.0*
1,1,.006,.0345,0.0*
20,1,.006,.0345,0.0,.0184,.0046,0.0*
1,1,.006,.0184,.0046*
20,1,.006,.0184,.0046,-.0529,.0046,0.0*
1,1,.006,-.0529,.0046*
%
%ADD14MACRO14*%
%AMMACRO16*
1,1,.006,.05793,.06583*
20,1,.006,.05793,.06583,.04213,.07373,0.0*
1,1,.006,.04213,.07373*
20,1,.006,.04213,.07373,.0237,.079,0.0*
1,1,.006,.0237,.079*
20,1,.006,.0237,.079,.00264,.079,0.0*
1,1,.006,.00264,.079*
20,1,.006,.00264,.079,-.02107,.0711,0.0*
1,1,.006,-.02107,.0711*
20,1,.006,-.02107,.0711,-.0395,.05793,0.0*
1,1,.006,-.0395,.05793*
20,1,.006,-.0395,.05793,-.05267,.04213,0.0*
1,1,.006,-.05267,.04213*
20,1,.006,-.05267,.04213,-.0632,.0158,0.0*
1,1,.006,-.0632,.0158*
20,1,.006,-.0632,.0158,-.06584,-.0079,0.0*
1,1,.006,-.06584,-.0079*
20,1,.006,-.06584,-.0079,-.06057,-.0316,0.0*
1,1,.006,-.06057,-.0316*
20,1,.006,-.06057,-.0316,-.05267,-.0474,0.0*
1,1,.006,-.05267,-.0474*
20,1,.006,-.05267,-.0474,-.03687,-.0632,0.0*
1,1,.006,-.03687,-.0632*
20,1,.006,-.03687,-.0632,-.01843,-.07373,0.0*
1,1,.006,-.01843,-.07373*
20,1,.006,-.01843,-.07373,0.0,-.079,0.0*
1,1,.006,0.0,-.079*
20,1,.006,0.0,-.079,.01843,-.079,0.0*
1,1,.006,.01843,-.079*
20,1,.006,.01843,-.079,.03687,-.07373,0.0*
1,1,.006,.03687,-.07373*
20,1,.006,.03687,-.07373,.05267,-.06584,0.0*
1,1,.006,.05267,-.06584*
20,1,.006,.05267,-.06584,.06584,-.05531,0.0*
1,1,.006,.06584,-.05531*
%
%ADD16MACRO16*%
%AMMACRO35*
1,1,.006,-.04363,-.0595*
20,1,.006,-.04363,-.0595,-.04363,.0595,0.0*
1,1,.006,-.04363,.0595*
1,1,.006,.03173,.0595*
20,1,.006,.03173,.0595,-.04363,-.01389,0.0*
1,1,.006,-.04363,-.01389*
1,1,.006,.04363,-.0595*
20,1,.006,.04363,-.0595,-.00992,.01983,0.0*
1,1,.006,-.00992,.01983*
%
%ADD35MACRO35*%
%AMMACRO33*
1,1,.006,.00728,0.0*
20,1,.006,.00728,0.0,0.0,-.00728,0.0*
1,1,.006,0.0,-.00728*
20,1,.006,0.0,-.00728,-.00728,0.0,0.0*
1,1,.006,-.00728,0.0*
20,1,.006,-.00728,0.0,0.0,.00728,0.0*
1,1,.006,0.0,.00728*
20,1,.006,0.0,.00728,.00728,0.0,0.0*
1,1,.006,.00728,0.0*
1,1,.006,-.00231,-.00061*
20,1,.006,-.00231,-.00061,-.00146,.00024,0.0*
1,1,.006,-.00146,.00024*
20,1,.006,-.00146,.00024,-.00073,.00073,0.0*
1,1,.006,-.00073,.00073*
20,1,.006,-.00073,.00073,.00024,.00097,0.0*
1,1,.006,.00024,.00097*
20,1,.006,.00024,.00097,.00109,.00073,0.0*
1,1,.006,.00109,.00073*
20,1,.006,.00109,.00073,.0017,.00024,0.0*
1,1,.006,.0017,.00024*
20,1,.006,.0017,.00024,.00218,-.00049,0.0*
1,1,.006,.00218,-.00049*
20,1,.006,.00218,-.00049,.00231,-.00133,0.0*
1,1,.006,.00231,-.00133*
20,1,.006,.00231,-.00133,.00218,-.00206,0.0*
1,1,.006,.00218,-.00206*
20,1,.006,.00218,-.00206,.0017,-.00279,0.0*
1,1,.006,.0017,-.00279*
20,1,.006,.0017,-.00279,.00097,-.0034,0.0*
1,1,.006,.00097,-.0034*
20,1,.006,.00097,-.0034,.00012,-.00364,0.0*
1,1,.006,.00012,-.00364*
20,1,.006,.00012,-.00364,-.00085,-.0034,0.0*
1,1,.006,-.00085,-.0034*
20,1,.006,-.00085,-.0034,-.0017,-.00267,0.0*
1,1,.006,-.0017,-.00267*
20,1,.006,-.0017,-.00267,-.00218,-.00158,0.0*
1,1,.006,-.00218,-.00158*
20,1,.006,-.00218,-.00158,-.00231,-.00036,0.0*
1,1,.006,-.00231,-.00036*
20,1,.006,-.00231,-.00036,-.00206,.00121,0.0*
1,1,.006,-.00206,.00121*
20,1,.006,-.00206,.00121,-.0017,.00206,0.0*
1,1,.006,-.0017,.00206*
20,1,.006,-.0017,.00206,-.00109,.00291,0.0*
1,1,.006,-.00109,.00291*
20,1,.006,-.00109,.00291,-.00024,.00352,0.0*
1,1,.006,-.00024,.00352*
20,1,.006,-.00024,.00352,.00061,.00364,0.0*
1,1,.006,.00061,.00364*
20,1,.006,.00061,.00364,.00146,.0034,0.0*
1,1,.006,.00146,.0034*
20,1,.006,.00146,.0034,.00206,.00279,0.0*
1,1,.006,.00206,.00279*
%
%ADD33MACRO33*%
%AMMACRO21*
1,1,.006,-.0616,-.084*
20,1,.006,-.0616,-.084,-.0616,.084,0.0*
1,1,.006,-.0616,.084*
20,1,.006,-.0616,.084,-.0056,.084,0.0*
1,1,.006,-.0056,.084*
20,1,.006,-.0056,.084,.0168,.0756,0.0*
1,1,.006,.0168,.0756*
20,1,.006,.0168,.0756,.0336,.0644,0.0*
1,1,.006,.0336,.0644*
20,1,.006,.0336,.0644,.0476,.0476,0.0*
1,1,.006,.0476,.0476*
20,1,.006,.0476,.0476,.0588,.028,0.0*
1,1,.006,.0588,.028*
20,1,.006,.0588,.028,.0616,0.0,0.0*
1,1,.006,.0616,0.0*
20,1,.006,.0616,0.0,.0588,-.028,0.0*
1,1,.006,.0588,-.028*
20,1,.006,.0588,-.028,.0476,-.0476,0.0*
1,1,.006,.0476,-.0476*
20,1,.006,.0476,-.0476,.0336,-.0644,0.0*
1,1,.006,.0336,-.0644*
20,1,.006,.0336,-.0644,.0168,-.0756,0.0*
1,1,.006,.0168,-.0756*
20,1,.006,.0168,-.0756,-.0056,-.084,0.0*
1,1,.006,-.0056,-.084*
20,1,.006,-.0056,-.084,-.0616,-.084,0.0*
1,1,.006,-.0616,-.084*
%
%ADD21MACRO21*%
%AMMACRO32*
1,1,.006,-.03625,-.0435*
20,1,.006,-.03625,-.0435,0.0,.0435,0.0*
1,1,.006,0.0,.0435*
20,1,.006,0.0,.0435,.03625,-.0435,0.0*
1,1,.006,.03625,-.0435*
1,1,.006,.0232,-.01305*
20,1,.006,.0232,-.01305,-.0232,-.01305,0.0*
1,1,.006,-.0232,-.01305*
%
%ADD32MACRO32*%
%AMMACRO25*
1,1,.006,.0048,0.0*
20,1,.006,.0048,0.0,.0208,0.0,0.0*
1,1,.006,.0208,0.0*
20,1,.006,.0208,0.0,.0208,-.0144,0.0*
1,1,.006,.0208,-.0144*
20,1,.006,.0208,-.0144,.016,-.0192,0.0*
1,1,.006,.016,-.0192*
20,1,.006,.016,-.0192,.0104,-.0224,0.0*
1,1,.006,.0104,-.0224*
20,1,.006,.0104,-.0224,.0024,-.024,0.0*
1,1,.006,.0024,-.024*
20,1,.006,.0024,-.024,-.0056,-.0224,0.0*
1,1,.006,-.0056,-.0224*
20,1,.006,-.0056,-.0224,-.0112,-.0192,0.0*
1,1,.006,-.0112,-.0192*
20,1,.006,-.0112,-.0192,-.016,-.0144,0.0*
1,1,.006,-.016,-.0144*
20,1,.006,-.016,-.0144,-.0192,-.0088,0.0*
1,1,.006,-.0192,-.0088*
20,1,.006,-.0192,-.0088,-.0208,-.0024,0.0*
1,1,.006,-.0208,-.0024*
20,1,.006,-.0208,-.0024,-.0208,.0032,0.0*
1,1,.006,-.0208,.0032*
20,1,.006,-.0208,.0032,-.0192,.008,0.0*
1,1,.006,-.0192,.008*
20,1,.006,-.0192,.008,-.016,.0136,0.0*
1,1,.006,-.016,.0136*
20,1,.006,-.016,.0136,-.0112,.0184,0.0*
1,1,.006,-.0112,.0184*
20,1,.006,-.0112,.0184,-.0064,.0216,0.0*
1,1,.006,-.0064,.0216*
20,1,.006,-.0064,.0216,0.0,.024,0.0*
1,1,.006,0.0,.024*
20,1,.006,0.0,.024,.0056,.024,0.0*
1,1,.006,.0056,.024*
20,1,.006,.0056,.024,.012,.0224,0.0*
1,1,.006,.012,.0224*
20,1,.006,.012,.0224,.0168,.0192,0.0*
1,1,.006,.0168,.0192*
%
%ADD25MACRO25*%
%AMMACRO30*
1,1,.006,-.0188,.047*
20,1,.006,-.0188,.047,.0188,.047,0.0*
1,1,.006,.0188,.047*
1,1,.006,0.0,.047*
20,1,.006,0.0,.047,0.0,-.047,0.0*
1,1,.006,0.0,-.047*
1,1,.006,-.0188,-.047*
20,1,.006,-.0188,-.047,.0188,-.047,0.0*
1,1,.006,.0188,-.047*
%
%ADD30MACRO30*%
%AMMACRO12*
1,1,.006,-.0301,-.043*
20,1,.006,-.0301,-.043,-.0301,.043,0.0*
1,1,.006,-.0301,.043*
1,1,.006,.0301,.043*
20,1,.006,.0301,.043,.0301,-.043,0.0*
1,1,.006,.0301,-.043*
1,1,.006,.0301,0.0*
20,1,.006,.0301,0.0,-.0301,0.0,0.0*
1,1,.006,-.0301,0.0*
%
%ADD12MACRO12*%
%AMMACRO29*
1,1,.006,-.03233,-.0291*
20,1,.006,-.03233,-.0291,-.02425,-.0388,0.0*
1,1,.006,-.02425,-.0388*
20,1,.006,-.02425,-.0388,-.01455,-.04527,0.0*
1,1,.006,-.01455,-.04527*
20,1,.006,-.01455,-.04527,-.00323,-.0485,0.0*
1,1,.006,-.00323,-.0485*
20,1,.006,-.00323,-.0485,.0097,-.04527,0.0*
1,1,.006,.0097,-.04527*
20,1,.006,.0097,-.04527,.0194,-.0388,0.0*
1,1,.006,.0194,-.0388*
20,1,.006,.0194,-.0388,.0291,-.0291,0.0*
1,1,.006,.0291,-.0291*
20,1,.006,.0291,-.0291,.03233,-.01617,0.0*
1,1,.006,.03233,-.01617*
20,1,.006,.03233,-.01617,.03233,.0485,0.0*
1,1,.006,.03233,.0485*
%
%ADD29MACRO29*%
%AMMACRO19*
1,1,.006,.005,0.0*
20,1,.006,.005,0.0,.0025,.00433,0.0*
1,1,.006,.0025,.00433*
20,1,.006,.0025,.00433,-.0025,.00433,0.0*
1,1,.006,-.0025,.00433*
20,1,.006,-.0025,.00433,-.005,0.0,0.0*
1,1,.006,-.005,0.0*
20,1,.006,-.005,0.0,-.0025,-.00433,0.0*
1,1,.006,-.0025,-.00433*
20,1,.006,-.0025,-.00433,.0025,-.00433,0.0*
1,1,.006,.0025,-.00433*
20,1,.006,.0025,-.00433,.005,0.0,0.0*
1,1,.006,.005,0.0*
1,1,.006,-.00183,-.0015*
20,1,.006,-.00183,-.0015,-.00133,-.00208,0.0*
1,1,.006,-.00133,-.00208*
20,1,.006,-.00133,-.00208,-.00067,-.00242,0.0*
1,1,.006,-.00067,-.00242*
20,1,.006,-.00067,-.00242,.00008,-.0025,0.0*
1,1,.006,.00008,-.0025*
20,1,.006,.00008,-.0025,.00075,-.00242,0.0*
1,1,.006,.00075,-.00242*
20,1,.006,.00075,-.00242,.00142,-.002,0.0*
1,1,.006,.00142,-.002*
20,1,.006,.00142,-.002,.00183,-.0015,0.0*
1,1,.006,.00183,-.0015*
20,1,.006,.00183,-.0015,.00192,-.001,0.0*
1,1,.006,.00192,-.001*
20,1,.006,.00192,-.001,.00175,-.00042,0.0*
1,1,.006,.00175,-.00042*
20,1,.006,.00175,-.00042,.00117,0.0,0.0*
1,1,.006,.00117,0.0*
20,1,.006,.00117,0.0,.00058,.00017,0.0*
1,1,.006,.00058,.00017*
20,1,.006,.00058,.00017,-.00017,.00017,0.0*
1,1,.006,-.00017,.00017*
1,1,.006,.00058,.00017*
20,1,.006,.00058,.00017,.00108,.00042,0.0*
1,1,.006,.00108,.00042*
20,1,.006,.00108,.00042,.0015,.00083,0.0*
1,1,.006,.0015,.00083*
20,1,.006,.0015,.00083,.00167,.00133,0.0*
1,1,.006,.00167,.00133*
20,1,.006,.00167,.00133,.0015,.00183,0.0*
1,1,.006,.0015,.00183*
20,1,.006,.0015,.00183,.00108,.00225,0.0*
1,1,.006,.00108,.00225*
20,1,.006,.00108,.00225,.00033,.0025,0.0*
1,1,.006,.00033,.0025*
20,1,.006,.00033,.0025,-.00042,.00242,0.0*
1,1,.006,-.00042,.00242*
20,1,.006,-.00042,.00242,-.00117,.00208,0.0*
1,1,.006,-.00117,.00208*
%
%ADD19MACRO19*%
%AMMACRO24*
1,1,.006,-.016,-.012*
20,1,.006,-.016,-.012,-.016,.012,0.0*
1,1,.006,-.016,.012*
20,1,.006,-.016,.012,-.015757,.014778,0.0*
1,1,.006,-.015757,.014778*
20,1,.006,-.015757,.014778,-.015035,.017472,0.0*
1,1,.006,-.015035,.017472*
20,1,.006,-.015035,.017472,-.013856,.02,0.0*
1,1,.006,-.013856,.02*
20,1,.006,-.013856,.02,-.012257,.022285,0.0*
1,1,.006,-.012257,.022285*
20,1,.006,-.012257,.022285,-.010285,.024257,0.0*
1,1,.006,-.010285,.024257*
20,1,.006,-.010285,.024257,-.008,.025856,0.0*
1,1,.006,-.008,.025856*
20,1,.006,-.008,.025856,-.005472,.027035,0.0*
1,1,.006,-.005472,.027035*
20,1,.006,-.005472,.027035,-.002778,.027757,0.0*
1,1,.006,-.002778,.027757*
20,1,.006,-.002778,.027757,0.0,.028,0.0*
1,1,.006,0.0,.028*
20,1,.006,0.0,.028,.002778,.027757,0.0*
1,1,.006,.002778,.027757*
20,1,.006,.002778,.027757,.005472,.027035,0.0*
1,1,.006,.005472,.027035*
20,1,.006,.005472,.027035,.008,.025856,0.0*
1,1,.006,.008,.025856*
20,1,.006,.008,.025856,.010285,.024257,0.0*
1,1,.006,.010285,.024257*
20,1,.006,.010285,.024257,.012257,.022285,0.0*
1,1,.006,.012257,.022285*
20,1,.006,.012257,.022285,.013856,.02,0.0*
1,1,.006,.013856,.02*
20,1,.006,.013856,.02,.015035,.017472,0.0*
1,1,.006,.015035,.017472*
20,1,.006,.015035,.017472,.015757,.014778,0.0*
1,1,.006,.015757,.014778*
20,1,.006,.015757,.014778,.016,.012,0.0*
1,1,.006,.016,.012*
20,1,.006,.016,.012,.016,-.012,0.0*
1,1,.006,.016,-.012*
20,1,.006,.016,-.012,.015757,-.014778,0.0*
1,1,.006,.015757,-.014778*
20,1,.006,.015757,-.014778,.015035,-.017472,0.0*
1,1,.006,.015035,-.017472*
20,1,.006,.015035,-.017472,.013856,-.02,0.0*
1,1,.006,.013856,-.02*
20,1,.006,.013856,-.02,.012257,-.022285,0.0*
1,1,.006,.012257,-.022285*
20,1,.006,.012257,-.022285,.010285,-.024257,0.0*
1,1,.006,.010285,-.024257*
20,1,.006,.010285,-.024257,.008,-.025856,0.0*
1,1,.006,.008,-.025856*
20,1,.006,.008,-.025856,.005472,-.027035,0.0*
1,1,.006,.005472,-.027035*
20,1,.006,.005472,-.027035,.002778,-.027757,0.0*
1,1,.006,.002778,-.027757*
20,1,.006,.002778,-.027757,0.0,-.028,0.0*
1,1,.006,0.0,-.028*
20,1,.006,0.0,-.028,-.002778,-.027757,0.0*
1,1,.006,-.002778,-.027757*
20,1,.006,-.002778,-.027757,-.005472,-.027035,0.0*
1,1,.006,-.005472,-.027035*
20,1,.006,-.005472,-.027035,-.008,-.025856,0.0*
1,1,.006,-.008,-.025856*
20,1,.006,-.008,-.025856,-.010285,-.024257,0.0*
1,1,.006,-.010285,-.024257*
20,1,.006,-.010285,-.024257,-.012257,-.022285,0.0*
1,1,.006,-.012257,-.022285*
20,1,.006,-.012257,-.022285,-.013856,-.02,0.0*
1,1,.006,-.013856,-.02*
20,1,.006,-.013856,-.02,-.015035,-.017472,0.0*
1,1,.006,-.015035,-.017472*
20,1,.006,-.015035,-.017472,-.015757,-.014778,0.0*
1,1,.006,-.015757,-.014778*
20,1,.006,-.015757,-.014778,-.016,-.012,0.0*
1,1,.006,-.016,-.012*
1,1,.006,-.008,-.008*
20,1,.006,-.008,-.008,-.01013,-.00773,0.0*
1,1,.006,-.01013,-.00773*
20,1,.006,-.01013,-.00773,-.012,-.00667,0.0*
1,1,.006,-.012,-.00667*
20,1,.006,-.012,-.00667,-.0136,-.00507,0.0*
1,1,.006,-.0136,-.00507*
20,1,.006,-.0136,-.00507,-.01467,-.0032,0.0*
1,1,.006,-.01467,-.0032*
20,1,.006,-.01467,-.0032,-.0152,-.00107,0.0*
1,1,.006,-.0152,-.00107*
20,1,.006,-.0152,-.00107,-.0152,.00107,0.0*
1,1,.006,-.0152,.00107*
20,1,.006,-.0152,.00107,-.01467,.0032,0.0*
1,1,.006,-.01467,.0032*
20,1,.006,-.01467,.0032,-.0136,.00507,0.0*
1,1,.006,-.0136,.00507*
20,1,.006,-.0136,.00507,-.012,.00667,0.0*
1,1,.006,-.012,.00667*
20,1,.006,-.012,.00667,-.01013,.00773,0.0*
1,1,.006,-.01013,.00773*
20,1,.006,-.01013,.00773,-.008,.008,0.0*
1,1,.006,-.008,.008*
20,1,.006,-.008,.008,-.00587,.00773,0.0*
1,1,.006,-.00587,.00773*
20,1,.006,-.00587,.00773,-.004,.00667,0.0*
1,1,.006,-.004,.00667*
20,1,.006,-.004,.00667,-.0024,.00507,0.0*
1,1,.006,-.0024,.00507*
20,1,.006,-.0024,.00507,-.00133,.0032,0.0*
1,1,.006,-.00133,.0032*
20,1,.006,-.00133,.0032,-.0008,.00107,0.0*
1,1,.006,-.0008,.00107*
20,1,.006,-.0008,.00107,-.0008,-.00107,0.0*
1,1,.006,-.0008,-.00107*
20,1,.006,-.0008,-.00107,-.00133,-.0032,0.0*
1,1,.006,-.00133,-.0032*
20,1,.006,-.00133,-.0032,-.0024,-.00507,0.0*
1,1,.006,-.0024,-.00507*
20,1,.006,-.0024,-.00507,-.004,-.00667,0.0*
1,1,.006,-.004,-.00667*
20,1,.006,-.004,-.00667,-.00587,-.00773,0.0*
1,1,.006,-.00587,-.00773*
20,1,.006,-.00587,-.00773,-.008,-.008,0.0*
1,1,.006,-.008,-.008*
1,1,.006,.00134,-.008*
20,1,.006,.00134,-.008,.00801,.008,0.0*
1,1,.006,.00801,.008*
20,1,.006,.00801,.008,.01468,-.008,0.0*
1,1,.006,.01468,-.008*
1,1,.006,.01228,-.0024*
20,1,.006,.01228,-.0024,.00374,-.0024,0.0*
1,1,.006,.00374,-.0024*
%
%ADD24MACRO24*%
%AMMACRO11*
1,1,.006,.02,0.0*
20,1,.006,.02,0.0,.019696,-.003473,0.0*
1,1,.006,.019696,-.003473*
20,1,.006,.019696,-.003473,.018794,-.00684,0.0*
1,1,.006,.018794,-.00684*
20,1,.006,.018794,-.00684,.017321,-.01,0.0*
1,1,.006,.017321,-.01*
20,1,.006,.017321,-.01,.015321,-.012856,0.0*
1,1,.006,.015321,-.012856*
20,1,.006,.015321,-.012856,.012856,-.015321,0.0*
1,1,.006,.012856,-.015321*
20,1,.006,.012856,-.015321,.01,-.017321,0.0*
1,1,.006,.01,-.017321*
20,1,.006,.01,-.017321,.00684,-.018794,0.0*
1,1,.006,.00684,-.018794*
20,1,.006,.00684,-.018794,.003473,-.019696,0.0*
1,1,.006,.003473,-.019696*
20,1,.006,.003473,-.019696,0.0,-.02,0.0*
1,1,.006,0.0,-.02*
20,1,.006,0.0,-.02,-.003473,-.019696,0.0*
1,1,.006,-.003473,-.019696*
20,1,.006,-.003473,-.019696,-.00684,-.018794,0.0*
1,1,.006,-.00684,-.018794*
20,1,.006,-.00684,-.018794,-.01,-.017321,0.0*
1,1,.006,-.01,-.017321*
20,1,.006,-.01,-.017321,-.012856,-.015321,0.0*
1,1,.006,-.012856,-.015321*
20,1,.006,-.012856,-.015321,-.015321,-.012856,0.0*
1,1,.006,-.015321,-.012856*
20,1,.006,-.015321,-.012856,-.017321,-.01,0.0*
1,1,.006,-.017321,-.01*
20,1,.006,-.017321,-.01,-.018794,-.00684,0.0*
1,1,.006,-.018794,-.00684*
20,1,.006,-.018794,-.00684,-.019696,-.003473,0.0*
1,1,.006,-.019696,-.003473*
20,1,.006,-.019696,-.003473,-.02,0.0,0.0*
1,1,.006,-.02,0.0*
20,1,.006,-.02,0.0,-.019696,.003473,0.0*
1,1,.006,-.019696,.003473*
20,1,.006,-.019696,.003473,-.018794,.00684,0.0*
1,1,.006,-.018794,.00684*
20,1,.006,-.018794,.00684,-.017321,.01,0.0*
1,1,.006,-.017321,.01*
20,1,.006,-.017321,.01,-.015321,.012856,0.0*
1,1,.006,-.015321,.012856*
20,1,.006,-.015321,.012856,-.012856,.015321,0.0*
1,1,.006,-.012856,.015321*
20,1,.006,-.012856,.015321,-.01,.017321,0.0*
1,1,.006,-.01,.017321*
20,1,.006,-.01,.017321,-.00684,.018794,0.0*
1,1,.006,-.00684,.018794*
20,1,.006,-.00684,.018794,-.003473,.019696,0.0*
1,1,.006,-.003473,.019696*
20,1,.006,-.003473,.019696,0.0,.02,0.0*
1,1,.006,0.0,.02*
20,1,.006,0.0,.02,.003473,.019696,0.0*
1,1,.006,.003473,.019696*
20,1,.006,.003473,.019696,.00684,.018794,0.0*
1,1,.006,.00684,.018794*
20,1,.006,.00684,.018794,.01,.017321,0.0*
1,1,.006,.01,.017321*
20,1,.006,.01,.017321,.012856,.015321,0.0*
1,1,.006,.012856,.015321*
20,1,.006,.012856,.015321,.015321,.012856,0.0*
1,1,.006,.015321,.012856*
20,1,.006,.015321,.012856,.017321,.01,0.0*
1,1,.006,.017321,.01*
20,1,.006,.017321,.01,.018794,.00684,0.0*
1,1,.006,.018794,.00684*
20,1,.006,.018794,.00684,.019696,.003473,0.0*
1,1,.006,.019696,.003473*
20,1,.006,.019696,.003473,.02,0.0,0.0*
1,1,.006,.02,0.0*
1,1,.006,-.01,-.01*
20,1,.006,-.01,-.01,-.01,.01,0.0*
1,1,.006,-.01,.01*
20,1,.006,-.01,.01,-.014,.006,0.0*
1,1,.006,-.014,.006*
1,1,.006,-.014,-.01*
20,1,.006,-.014,-.01,-.006,-.01,0.0*
1,1,.006,-.006,-.01*
1,1,.006,.01001,-.01*
20,1,.006,.01001,-.01,.01001,.01,0.0*
1,1,.006,.01001,.01*
20,1,.006,.01001,.01,.00601,.006,0.0*
1,1,.006,.00601,.006*
1,1,.006,.00601,-.01*
20,1,.006,.00601,-.01,.01401,-.01,0.0*
1,1,.006,.01401,-.01*
%
%ADD11MACRO11*%
%AMMACRO23*
1,1,.006,-.016,-.0255*
20,1,.006,-.016,-.0255,-.016,.0255,0.0*
1,1,.006,-.016,.0255*
20,1,.006,-.016,.0255,-.015757,.028278,0.0*
1,1,.006,-.015757,.028278*
20,1,.006,-.015757,.028278,-.015035,.030972,0.0*
1,1,.006,-.015035,.030972*
20,1,.006,-.015035,.030972,-.013856,.0335,0.0*
1,1,.006,-.013856,.0335*
20,1,.006,-.013856,.0335,-.012257,.035785,0.0*
1,1,.006,-.012257,.035785*
20,1,.006,-.012257,.035785,-.010285,.037757,0.0*
1,1,.006,-.010285,.037757*
20,1,.006,-.010285,.037757,-.008,.039356,0.0*
1,1,.006,-.008,.039356*
20,1,.006,-.008,.039356,-.005472,.040535,0.0*
1,1,.006,-.005472,.040535*
20,1,.006,-.005472,.040535,-.002778,.041257,0.0*
1,1,.006,-.002778,.041257*
20,1,.006,-.002778,.041257,0.0,.0415,0.0*
1,1,.006,0.0,.0415*
20,1,.006,0.0,.0415,.002778,.041257,0.0*
1,1,.006,.002778,.041257*
20,1,.006,.002778,.041257,.005472,.040535,0.0*
1,1,.006,.005472,.040535*
20,1,.006,.005472,.040535,.008,.039356,0.0*
1,1,.006,.008,.039356*
20,1,.006,.008,.039356,.010285,.037757,0.0*
1,1,.006,.010285,.037757*
20,1,.006,.010285,.037757,.012257,.035785,0.0*
1,1,.006,.012257,.035785*
20,1,.006,.012257,.035785,.013856,.0335,0.0*
1,1,.006,.013856,.0335*
20,1,.006,.013856,.0335,.015035,.030972,0.0*
1,1,.006,.015035,.030972*
20,1,.006,.015035,.030972,.015757,.028278,0.0*
1,1,.006,.015757,.028278*
20,1,.006,.015757,.028278,.016,.0255,0.0*
1,1,.006,.016,.0255*
20,1,.006,.016,.0255,.016,-.0255,0.0*
1,1,.006,.016,-.0255*
20,1,.006,.016,-.0255,.015757,-.028278,0.0*
1,1,.006,.015757,-.028278*
20,1,.006,.015757,-.028278,.015035,-.030972,0.0*
1,1,.006,.015035,-.030972*
20,1,.006,.015035,-.030972,.013856,-.0335,0.0*
1,1,.006,.013856,-.0335*
20,1,.006,.013856,-.0335,.012257,-.035785,0.0*
1,1,.006,.012257,-.035785*
20,1,.006,.012257,-.035785,.010285,-.037757,0.0*
1,1,.006,.010285,-.037757*
20,1,.006,.010285,-.037757,.008,-.039356,0.0*
1,1,.006,.008,-.039356*
20,1,.006,.008,-.039356,.005472,-.040535,0.0*
1,1,.006,.005472,-.040535*
20,1,.006,.005472,-.040535,.002778,-.041257,0.0*
1,1,.006,.002778,-.041257*
20,1,.006,.002778,-.041257,0.0,-.0415,0.0*
1,1,.006,0.0,-.0415*
20,1,.006,0.0,-.0415,-.002778,-.041257,0.0*
1,1,.006,-.002778,-.041257*
20,1,.006,-.002778,-.041257,-.005472,-.040535,0.0*
1,1,.006,-.005472,-.040535*
20,1,.006,-.005472,-.040535,-.008,-.039356,0.0*
1,1,.006,-.008,-.039356*
20,1,.006,-.008,-.039356,-.010285,-.037757,0.0*
1,1,.006,-.010285,-.037757*
20,1,.006,-.010285,-.037757,-.012257,-.035785,0.0*
1,1,.006,-.012257,-.035785*
20,1,.006,-.012257,-.035785,-.013856,-.0335,0.0*
1,1,.006,-.013856,-.0335*
20,1,.006,-.013856,-.0335,-.015035,-.030972,0.0*
1,1,.006,-.015035,-.030972*
20,1,.006,-.015035,-.030972,-.015757,-.028278,0.0*
1,1,.006,-.015757,-.028278*
20,1,.006,-.015757,-.028278,-.016,-.0255,0.0*
1,1,.006,-.016,-.0255*
1,1,.006,-.008,-.008*
20,1,.006,-.008,-.008,-.01013,-.00773,0.0*
1,1,.006,-.01013,-.00773*
20,1,.006,-.01013,-.00773,-.012,-.00667,0.0*
1,1,.006,-.012,-.00667*
20,1,.006,-.012,-.00667,-.0136,-.00507,0.0*
1,1,.006,-.0136,-.00507*
20,1,.006,-.0136,-.00507,-.01467,-.0032,0.0*
1,1,.006,-.01467,-.0032*
20,1,.006,-.01467,-.0032,-.0152,-.00107,0.0*
1,1,.006,-.0152,-.00107*
20,1,.006,-.0152,-.00107,-.0152,.00107,0.0*
1,1,.006,-.0152,.00107*
20,1,.006,-.0152,.00107,-.01467,.0032,0.0*
1,1,.006,-.01467,.0032*
20,1,.006,-.01467,.0032,-.0136,.00507,0.0*
1,1,.006,-.0136,.00507*
20,1,.006,-.0136,.00507,-.012,.00667,0.0*
1,1,.006,-.012,.00667*
20,1,.006,-.012,.00667,-.01013,.00773,0.0*
1,1,.006,-.01013,.00773*
20,1,.006,-.01013,.00773,-.008,.008,0.0*
1,1,.006,-.008,.008*
20,1,.006,-.008,.008,-.00587,.00773,0.0*
1,1,.006,-.00587,.00773*
20,1,.006,-.00587,.00773,-.004,.00667,0.0*
1,1,.006,-.004,.00667*
20,1,.006,-.004,.00667,-.0024,.00507,0.0*
1,1,.006,-.0024,.00507*
20,1,.006,-.0024,.00507,-.00133,.0032,0.0*
1,1,.006,-.00133,.0032*
20,1,.006,-.00133,.0032,-.0008,.00107,0.0*
1,1,.006,-.0008,.00107*
20,1,.006,-.0008,.00107,-.0008,-.00107,0.0*
1,1,.006,-.0008,-.00107*
20,1,.006,-.0008,-.00107,-.00133,-.0032,0.0*
1,1,.006,-.00133,-.0032*
20,1,.006,-.00133,-.0032,-.0024,-.00507,0.0*
1,1,.006,-.0024,-.00507*
20,1,.006,-.0024,-.00507,-.004,-.00667,0.0*
1,1,.006,-.004,-.00667*
20,1,.006,-.004,-.00667,-.00587,-.00773,0.0*
1,1,.006,-.00587,-.00773*
20,1,.006,-.00587,-.00773,-.008,-.008,0.0*
1,1,.006,-.008,-.008*
1,1,.006,.01014,.00053*
20,1,.006,.01014,.00053,.01121,.00133,0.0*
1,1,.006,.01121,.00133*
20,1,.006,.01121,.00133,.01201,.00267,0.0*
1,1,.006,.01201,.00267*
20,1,.006,.01201,.00267,.01254,.00453,0.0*
1,1,.006,.01254,.00453*
20,1,.006,.01254,.00453,.01201,.00613,0.0*
1,1,.006,.01201,.00613*
20,1,.006,.01201,.00613,.01094,.0072,0.0*
1,1,.006,.01094,.0072*
20,1,.006,.01094,.0072,.00908,.008,0.0*
1,1,.006,.00908,.008*
20,1,.006,.00908,.008,.00188,.008,0.0*
1,1,.006,.00188,.008*
20,1,.006,.00188,.008,.00188,-.008,0.0*
1,1,.006,.00188,-.008*
20,1,.006,.00188,-.008,.01068,-.008,0.0*
1,1,.006,.01068,-.008*
20,1,.006,.01068,-.008,.01254,-.00693,0.0*
1,1,.006,.01254,-.00693*
20,1,.006,.01254,-.00693,.01361,-.00533,0.0*
1,1,.006,.01361,-.00533*
20,1,.006,.01361,-.00533,.01414,-.00347,0.0*
1,1,.006,.01414,-.00347*
20,1,.006,.01414,-.00347,.01361,-.0016,0.0*
1,1,.006,.01361,-.0016*
20,1,.006,.01361,-.0016,.01201,0.0,0.0*
1,1,.006,.01201,0.0*
20,1,.006,.01201,0.0,.01014,.00053,0.0*
1,1,.006,.01014,.00053*
20,1,.006,.01014,.00053,.00188,.00053,0.0*
1,1,.006,.00188,.00053*
%
%ADD23MACRO23*%
%AMMACRO17*
1,1,.006,0.0,.006*
20,1,.006,0.0,.006,-.005196,.003,0.0*
1,1,.006,-.005196,.003*
20,1,.006,-.005196,.003,-.005196,-.003,0.0*
1,1,.006,-.005196,-.003*
20,1,.006,-.005196,-.003,0.0,-.006,0.0*
1,1,.006,0.0,-.006*
20,1,.006,0.0,-.006,.005196,-.003,0.0*
1,1,.006,.005196,-.003*
20,1,.006,.005196,-.003,.005196,.003,0.0*
1,1,.006,.005196,.003*
20,1,.006,.005196,.003,0.0,.006,0.0*
1,1,.006,0.0,.006*
1,1,.006,.0012,-.003*
20,1,.006,.0012,-.003,.0012,.003,0.0*
1,1,.006,.0012,.003*
20,1,.006,.0012,.003,-.0025,-.0013,0.0*
1,1,.006,-.0025,-.0013*
20,1,.006,-.0025,-.0013,.0025,-.0013,0.0*
1,1,.006,.0025,-.0013*
%
%ADD17MACRO17*%
%AMMACRO15*
1,1,.006,-.067,.067*
20,1,.006,-.067,.067,.067,.067,0.0*
1,1,.006,.067,.067*
20,1,.006,.067,.067,.078634,.065982,0.0*
1,1,.006,.078634,.065982*
20,1,.006,.078634,.065982,.089915,.062959,0.0*
1,1,.006,.089915,.062959*
20,1,.006,.089915,.062959,.1005,.058024,0.0*
1,1,.006,.1005,.058024*
20,1,.006,.1005,.058024,.110067,.051325,0.0*
1,1,.006,.110067,.051325*
20,1,.006,.110067,.051325,.118325,.043067,0.0*
1,1,.006,.118325,.043067*
20,1,.006,.118325,.043067,.125024,.0335,0.0*
1,1,.006,.125024,.0335*
20,1,.006,.125024,.0335,.129959,.022915,0.0*
1,1,.006,.129959,.022915*
20,1,.006,.129959,.022915,.132982,.011634,0.0*
1,1,.006,.132982,.011634*
20,1,.006,.132982,.011634,.134,0.0,0.0*
1,1,.006,.134,0.0*
20,1,.006,.134,0.0,.132982,-.011634,0.0*
1,1,.006,.132982,-.011634*
20,1,.006,.132982,-.011634,.129959,-.022915,0.0*
1,1,.006,.129959,-.022915*
20,1,.006,.129959,-.022915,.125024,-.0335,0.0*
1,1,.006,.125024,-.0335*
20,1,.006,.125024,-.0335,.118325,-.043067,0.0*
1,1,.006,.118325,-.043067*
20,1,.006,.118325,-.043067,.110067,-.051325,0.0*
1,1,.006,.110067,-.051325*
20,1,.006,.110067,-.051325,.1005,-.058024,0.0*
1,1,.006,.1005,-.058024*
20,1,.006,.1005,-.058024,.089915,-.062959,0.0*
1,1,.006,.089915,-.062959*
20,1,.006,.089915,-.062959,.078634,-.065982,0.0*
1,1,.006,.078634,-.065982*
20,1,.006,.078634,-.065982,.067,-.067,0.0*
1,1,.006,.067,-.067*
20,1,.006,.067,-.067,-.067,-.067,0.0*
1,1,.006,-.067,-.067*
20,1,.006,-.067,-.067,-.078634,-.065982,0.0*
1,1,.006,-.078634,-.065982*
20,1,.006,-.078634,-.065982,-.089915,-.062959,0.0*
1,1,.006,-.089915,-.062959*
20,1,.006,-.089915,-.062959,-.1005,-.058024,0.0*
1,1,.006,-.1005,-.058024*
20,1,.006,-.1005,-.058024,-.110067,-.051325,0.0*
1,1,.006,-.110067,-.051325*
20,1,.006,-.110067,-.051325,-.118325,-.043067,0.0*
1,1,.006,-.118325,-.043067*
20,1,.006,-.118325,-.043067,-.125024,-.0335,0.0*
1,1,.006,-.125024,-.0335*
20,1,.006,-.125024,-.0335,-.129959,-.022915,0.0*
1,1,.006,-.129959,-.022915*
20,1,.006,-.129959,-.022915,-.132982,-.011634,0.0*
1,1,.006,-.132982,-.011634*
20,1,.006,-.132982,-.011634,-.134,0.0,0.0*
1,1,.006,-.134,0.0*
20,1,.006,-.134,0.0,-.132982,.011634,0.0*
1,1,.006,-.132982,.011634*
20,1,.006,-.132982,.011634,-.129959,.022915,0.0*
1,1,.006,-.129959,.022915*
20,1,.006,-.129959,.022915,-.125024,.0335,0.0*
1,1,.006,-.125024,.0335*
20,1,.006,-.125024,.0335,-.118325,.043067,0.0*
1,1,.006,-.118325,.043067*
20,1,.006,-.118325,.043067,-.110067,.051325,0.0*
1,1,.006,-.110067,.051325*
20,1,.006,-.110067,.051325,-.1005,.058024,0.0*
1,1,.006,-.1005,.058024*
20,1,.006,-.1005,.058024,-.089915,.062959,0.0*
1,1,.006,-.089915,.062959*
20,1,.006,-.089915,.062959,-.078634,.065982,0.0*
1,1,.006,-.078634,.065982*
20,1,.006,-.078634,.065982,-.067,.067,0.0*
1,1,.006,-.067,.067*
1,1,.006,-.0335,-.0335*
20,1,.006,-.0335,-.0335,-.04243,-.03238,0.0*
1,1,.006,-.04243,-.03238*
20,1,.006,-.04243,-.03238,-.05025,-.02792,0.0*
1,1,.006,-.05025,-.02792*
20,1,.006,-.05025,-.02792,-.05695,-.02122,0.0*
1,1,.006,-.05695,-.02122*
20,1,.006,-.05695,-.02122,-.06142,-.0134,0.0*
1,1,.006,-.06142,-.0134*
20,1,.006,-.06142,-.0134,-.06365,-.00447,0.0*
1,1,.006,-.06365,-.00447*
20,1,.006,-.06365,-.00447,-.06365,.00447,0.0*
1,1,.006,-.06365,.00447*
20,1,.006,-.06365,.00447,-.06142,.0134,0.0*
1,1,.006,-.06142,.0134*
20,1,.006,-.06142,.0134,-.05695,.02122,0.0*
1,1,.006,-.05695,.02122*
20,1,.006,-.05695,.02122,-.05025,.02792,0.0*
1,1,.006,-.05025,.02792*
20,1,.006,-.05025,.02792,-.04243,.03238,0.0*
1,1,.006,-.04243,.03238*
20,1,.006,-.04243,.03238,-.0335,.0335,0.0*
1,1,.006,-.0335,.0335*
20,1,.006,-.0335,.0335,-.02457,.03238,0.0*
1,1,.006,-.02457,.03238*
20,1,.006,-.02457,.03238,-.01675,.02792,0.0*
1,1,.006,-.01675,.02792*
20,1,.006,-.01675,.02792,-.01005,.02122,0.0*
1,1,.006,-.01005,.02122*
20,1,.006,-.01005,.02122,-.00558,.0134,0.0*
1,1,.006,-.00558,.0134*
20,1,.006,-.00558,.0134,-.00335,.00447,0.0*
1,1,.006,-.00335,.00447*
20,1,.006,-.00335,.00447,-.00335,-.00447,0.0*
1,1,.006,-.00335,-.00447*
20,1,.006,-.00335,-.00447,-.00558,-.0134,0.0*
1,1,.006,-.00558,-.0134*
20,1,.006,-.00558,-.0134,-.01005,-.02122,0.0*
1,1,.006,-.01005,-.02122*
20,1,.006,-.01005,-.02122,-.01675,-.02792,0.0*
1,1,.006,-.01675,-.02792*
20,1,.006,-.01675,-.02792,-.02457,-.03238,0.0*
1,1,.006,-.02457,-.03238*
20,1,.006,-.02457,-.03238,-.0335,-.0335,0.0*
1,1,.006,-.0335,-.0335*
1,1,.006,.05808,.02792*
20,1,.006,.05808,.02792,.05138,.03127,0.0*
1,1,.006,.05138,.03127*
20,1,.006,.05138,.03127,.04356,.0335,0.0*
1,1,.006,.04356,.0335*
20,1,.006,.04356,.0335,.03463,.0335,0.0*
1,1,.006,.03463,.0335*
20,1,.006,.03463,.0335,.02458,.03015,0.0*
1,1,.006,.02458,.03015*
20,1,.006,.02458,.03015,.01676,.02457,0.0*
1,1,.006,.01676,.02457*
20,1,.006,.01676,.02457,.01118,.01787,0.0*
1,1,.006,.01118,.01787*
20,1,.006,.01118,.01787,.00671,.0067,0.0*
1,1,.006,.00671,.0067*
20,1,.006,.00671,.0067,.00559,-.00335,0.0*
1,1,.006,.00559,-.00335*
20,1,.006,.00559,-.00335,.00783,-.0134,0.0*
1,1,.006,.00783,-.0134*
20,1,.006,.00783,-.0134,.01118,-.0201,0.0*
1,1,.006,.01118,-.0201*
20,1,.006,.01118,-.0201,.01788,-.0268,0.0*
1,1,.006,.01788,-.0268*
20,1,.006,.01788,-.0268,.02569,-.03127,0.0*
1,1,.006,.02569,-.03127*
20,1,.006,.02569,-.03127,.03351,-.0335,0.0*
1,1,.006,.03351,-.0335*
20,1,.006,.03351,-.0335,.04133,-.0335,0.0*
1,1,.006,.04133,-.0335*
20,1,.006,.04133,-.0335,.04914,-.03127,0.0*
1,1,.006,.04914,-.03127*
20,1,.006,.04914,-.03127,.05584,-.02792,0.0*
1,1,.006,.05584,-.02792*
20,1,.006,.05584,-.02792,.06143,-.02345,0.0*
1,1,.006,.06143,-.02345*
%
%ADD15MACRO15*%
%AMMACRO27*
1,1,.006,-.0105,.0035*
20,1,.006,-.0105,.0035,-.01034,.005323,0.0*
1,1,.006,-.01034,.005323*
20,1,.006,-.01034,.005323,-.009867,.007091,0.0*
1,1,.006,-.009867,.007091*
20,1,.006,-.009867,.007091,-.009093,.00875,0.0*
1,1,.006,-.009093,.00875*
20,1,.006,-.009093,.00875,-.008043,.010249,0.0*
1,1,.006,-.008043,.010249*
20,1,.006,-.008043,.010249,-.006749,.011543,0.0*
1,1,.006,-.006749,.011543*
20,1,.006,-.006749,.011543,-.00525,.012593,0.0*
1,1,.006,-.00525,.012593*
20,1,.006,-.00525,.012593,-.003591,.013367,0.0*
1,1,.006,-.003591,.013367*
20,1,.006,-.003591,.013367,-.001823,.01384,0.0*
1,1,.006,-.001823,.01384*
20,1,.006,-.001823,.01384,0.0,.014,0.0*
1,1,.006,0.0,.014*
20,1,.006,0.0,.014,.001823,.01384,0.0*
1,1,.006,.001823,.01384*
20,1,.006,.001823,.01384,.003591,.013367,0.0*
1,1,.006,.003591,.013367*
20,1,.006,.003591,.013367,.00525,.012593,0.0*
1,1,.006,.00525,.012593*
20,1,.006,.00525,.012593,.006749,.011543,0.0*
1,1,.006,.006749,.011543*
20,1,.006,.006749,.011543,.008043,.010249,0.0*
1,1,.006,.008043,.010249*
20,1,.006,.008043,.010249,.009093,.00875,0.0*
1,1,.006,.009093,.00875*
20,1,.006,.009093,.00875,.009867,.007091,0.0*
1,1,.006,.009867,.007091*
20,1,.006,.009867,.007091,.01034,.005323,0.0*
1,1,.006,.01034,.005323*
20,1,.006,.01034,.005323,.0105,.0035,0.0*
1,1,.006,.0105,.0035*
20,1,.006,.0105,.0035,.0105,-.0035,0.0*
1,1,.006,.0105,-.0035*
20,1,.006,.0105,-.0035,.01034,-.005323,0.0*
1,1,.006,.01034,-.005323*
20,1,.006,.01034,-.005323,.009867,-.007091,0.0*
1,1,.006,.009867,-.007091*
20,1,.006,.009867,-.007091,.009093,-.00875,0.0*
1,1,.006,.009093,-.00875*
20,1,.006,.009093,-.00875,.008043,-.010249,0.0*
1,1,.006,.008043,-.010249*
20,1,.006,.008043,-.010249,.006749,-.011543,0.0*
1,1,.006,.006749,-.011543*
20,1,.006,.006749,-.011543,.00525,-.012593,0.0*
1,1,.006,.00525,-.012593*
20,1,.006,.00525,-.012593,.003591,-.013367,0.0*
1,1,.006,.003591,-.013367*
20,1,.006,.003591,-.013367,.001823,-.01384,0.0*
1,1,.006,.001823,-.01384*
20,1,.006,.001823,-.01384,0.0,-.014,0.0*
1,1,.006,0.0,-.014*
20,1,.006,0.0,-.014,-.001823,-.01384,0.0*
1,1,.006,-.001823,-.01384*
20,1,.006,-.001823,-.01384,-.003591,-.013367,0.0*
1,1,.006,-.003591,-.013367*
20,1,.006,-.003591,-.013367,-.00525,-.012593,0.0*
1,1,.006,-.00525,-.012593*
20,1,.006,-.00525,-.012593,-.006749,-.011543,0.0*
1,1,.006,-.006749,-.011543*
20,1,.006,-.006749,-.011543,-.008043,-.010249,0.0*
1,1,.006,-.008043,-.010249*
20,1,.006,-.008043,-.010249,-.009093,-.00875,0.0*
1,1,.006,-.009093,-.00875*
20,1,.006,-.009093,-.00875,-.009867,-.007091,0.0*
1,1,.006,-.009867,-.007091*
20,1,.006,-.009867,-.007091,-.01034,-.005323,0.0*
1,1,.006,-.01034,-.005323*
20,1,.006,-.01034,-.005323,-.0105,-.0035,0.0*
1,1,.006,-.0105,-.0035*
20,1,.006,-.0105,-.0035,-.0105,.0035,0.0*
1,1,.006,-.0105,.0035*
1,1,.006,-.00298,-.00403*
20,1,.006,-.00298,-.00403,-.00175,-.0049,0.0*
1,1,.006,-.00175,-.0049*
20,1,.006,-.00175,-.0049,-.00035,-.00525,0.0*
1,1,.006,-.00035,-.00525*
20,1,.006,-.00035,-.00525,.00105,-.0049,0.0*
1,1,.006,.00105,-.0049*
20,1,.006,.00105,-.0049,.00227,-.00385,0.0*
1,1,.006,.00227,-.00385*
20,1,.006,.00227,-.00385,.00315,-.00227,0.0*
1,1,.006,.00315,-.00227*
20,1,.006,.00315,-.00227,.0035,-.0007,0.0*
1,1,.006,.0035,-.0007*
20,1,.006,.0035,-.0007,.0035,.00122,0.0*
1,1,.006,.0035,.00122*
20,1,.006,.0035,.00122,.00315,.0028,0.0*
1,1,.006,.00315,.0028*
20,1,.006,.00315,.0028,.00227,.0042,0.0*
1,1,.006,.00227,.0042*
20,1,.006,.00227,.0042,.00122,.0049,0.0*
1,1,.006,.00122,.0049*
20,1,.006,.00122,.0049,0.0,.00525,0.0*
1,1,.006,0.0,.00525*
20,1,.006,0.0,.00525,-.0014,.0049,0.0*
1,1,.006,-.0014,.0049*
20,1,.006,-.0014,.0049,-.00245,.0042,0.0*
1,1,.006,-.00245,.0042*
20,1,.006,-.00245,.0042,-.00315,.00315,0.0*
1,1,.006,-.00315,.00315*
20,1,.006,-.00315,.00315,-.0035,.00175,0.0*
1,1,.006,-.0035,.00175*
20,1,.006,-.0035,.00175,-.00315,.00053,0.0*
1,1,.006,-.00315,.00053*
20,1,.006,-.00315,.00053,-.00227,-.0007,0.0*
1,1,.006,-.00227,-.0007*
20,1,.006,-.00227,-.0007,-.00122,-.0014,0.0*
1,1,.006,-.00122,-.0014*
20,1,.006,-.00122,-.0014,0.0,-.00158,0.0*
1,1,.006,0.0,-.00158*
20,1,.006,0.0,-.00158,.0014,-.00123,0.0*
1,1,.006,.0014,-.00123*
20,1,.006,.0014,-.00123,.00245,-.00035,0.0*
1,1,.006,.00245,-.00035*
20,1,.006,.00245,-.00035,.0035,.00122,0.0*
1,1,.006,.0035,.00122*
%
%ADD27MACRO27*%
%AMMACRO31*
1,1,.006,.0175,.013125*
20,1,.006,.0175,.013125,.0175,-.013125,0.0*
1,1,.006,.0175,-.013125*
20,1,.006,.0175,-.013125,-.0175,-.013125,0.0*
1,1,.006,-.0175,-.013125*
20,1,.006,-.0175,-.013125,-.0175,.013125,0.0*
1,1,.006,-.0175,.013125*
20,1,.006,-.0175,.013125,.0175,.013125,0.0*
1,1,.006,.0175,.013125*
1,1,.006,-.00656,-.00656*
20,1,.006,-.00656,-.00656,-.00656,.00656,0.0*
1,1,.006,-.00656,.00656*
20,1,.006,-.00656,.00656,-.00918,.00394,0.0*
1,1,.006,-.00918,.00394*
1,1,.006,-.00918,-.00656*
20,1,.006,-.00918,-.00656,-.00394,-.00656,0.0*
1,1,.006,-.00394,-.00656*
1,1,.006,.00657,.00656*
20,1,.006,.00657,.00656,.00482,.00612,0.0*
1,1,.006,.00482,.00612*
20,1,.006,.00482,.00612,.00351,.00503,0.0*
1,1,.006,.00351,.00503*
20,1,.006,.00351,.00503,.00263,.00372,0.0*
1,1,.006,.00263,.00372*
20,1,.006,.00263,.00372,.00198,.00197,0.0*
1,1,.006,.00198,.00197*
20,1,.006,.00198,.00197,.00176,0.0,0.0*
1,1,.006,.00176,0.0*
20,1,.006,.00176,0.0,.00198,-.00197,0.0*
1,1,.006,.00198,-.00197*
20,1,.006,.00198,-.00197,.00263,-.00372,0.0*
1,1,.006,.00263,-.00372*
20,1,.006,.00263,-.00372,.00351,-.00503,0.0*
1,1,.006,.00351,-.00503*
20,1,.006,.00351,-.00503,.00482,-.00612,0.0*
1,1,.006,.00482,-.00612*
20,1,.006,.00482,-.00612,.00657,-.00656,0.0*
1,1,.006,.00657,-.00656*
20,1,.006,.00657,-.00656,.00832,-.00612,0.0*
1,1,.006,.00832,-.00612*
20,1,.006,.00832,-.00612,.00963,-.00503,0.0*
1,1,.006,.00963,-.00503*
20,1,.006,.00963,-.00503,.01051,-.00372,0.0*
1,1,.006,.01051,-.00372*
20,1,.006,.01051,-.00372,.01116,-.00197,0.0*
1,1,.006,.01116,-.00197*
20,1,.006,.01116,-.00197,.01138,0.0,0.0*
1,1,.006,.01138,0.0*
20,1,.006,.01138,0.0,.01116,.00197,0.0*
1,1,.006,.01116,.00197*
20,1,.006,.01116,.00197,.01051,.00372,0.0*
1,1,.006,.01051,.00372*
20,1,.006,.01051,.00372,.00963,.00503,0.0*
1,1,.006,.00963,.00503*
20,1,.006,.00963,.00503,.00832,.00612,0.0*
1,1,.006,.00832,.00612*
20,1,.006,.00832,.00612,.00657,.00656,0.0*
1,1,.006,.00657,.00656*
%
%ADD31MACRO31*%
%AMMACRO10*
1,1,.006,0.0,.008*
20,1,.006,0.0,.008,.008,-.008,0.0*
1,1,.006,.008,-.008*
20,1,.006,.008,-.008,-.008,-.008,0.0*
1,1,.006,-.008,-.008*
20,1,.006,-.008,-.008,0.0,.008,0.0*
1,1,.006,0.0,.008*
1,1,.006,-.00027,-.004*
20,1,.006,-.00027,-.004,0.0,-.00227,0.0*
1,1,.006,0.0,-.00227*
20,1,.006,0.0,-.00227,.0004,-.0008,0.0*
1,1,.006,.0004,-.0008*
20,1,.006,.0004,-.0008,.00093,.00053,0.0*
1,1,.006,.00093,.00053*
20,1,.006,.00093,.00053,.0016,.002,0.0*
1,1,.006,.0016,.002*
20,1,.006,.0016,.002,.00267,.004,0.0*
1,1,.006,.00267,.004*
20,1,.006,.00267,.004,-.00267,.004,0.0*
1,1,.006,-.00267,.004*
%
%ADD10MACRO10*%
%AMMACRO34*
1,1,.006,-.002805,.008415*
20,1,.006,-.002805,.008415,.002805,.008415,0.0*
1,1,.006,.002805,.008415*
20,1,.006,.002805,.008415,.004266,.008287,0.0*
1,1,.006,.004266,.008287*
20,1,.006,.004266,.008287,.005683,.007908,0.0*
1,1,.006,.005683,.007908*
20,1,.006,.005683,.007908,.007012,.007288,0.0*
1,1,.006,.007012,.007288*
20,1,.006,.007012,.007288,.008214,.006446,0.0*
1,1,.006,.008214,.006446*
20,1,.006,.008214,.006446,.009251,.005409,0.0*
1,1,.006,.009251,.005409*
20,1,.006,.009251,.005409,.010093,.004208,0.0*
1,1,.006,.010093,.004208*
20,1,.006,.010093,.004208,.010713,.002878,0.0*
1,1,.006,.010713,.002878*
20,1,.006,.010713,.002878,.011092,.001461,0.0*
1,1,.006,.011092,.001461*
20,1,.006,.011092,.001461,.01122,0.0,0.0*
1,1,.006,.01122,0.0*
20,1,.006,.01122,0.0,.011092,-.001461,0.0*
1,1,.006,.011092,-.001461*
20,1,.006,.011092,-.001461,.010713,-.002878,0.0*
1,1,.006,.010713,-.002878*
20,1,.006,.010713,-.002878,.010093,-.004207,0.0*
1,1,.006,.010093,-.004207*
20,1,.006,.010093,-.004207,.009251,-.005409,0.0*
1,1,.006,.009251,-.005409*
20,1,.006,.009251,-.005409,.008214,-.006446,0.0*
1,1,.006,.008214,-.006446*
20,1,.006,.008214,-.006446,.007013,-.007288,0.0*
1,1,.006,.007013,-.007288*
20,1,.006,.007013,-.007288,.005683,-.007908,0.0*
1,1,.006,.005683,-.007908*
20,1,.006,.005683,-.007908,.004266,-.008287,0.0*
1,1,.006,.004266,-.008287*
20,1,.006,.004266,-.008287,.002805,-.008415,0.0*
1,1,.006,.002805,-.008415*
20,1,.006,.002805,-.008415,-.002805,-.008415,0.0*
1,1,.006,-.002805,-.008415*
20,1,.006,-.002805,-.008415,-.004266,-.008287,0.0*
1,1,.006,-.004266,-.008287*
20,1,.006,-.004266,-.008287,-.005683,-.007908,0.0*
1,1,.006,-.005683,-.007908*
20,1,.006,-.005683,-.007908,-.007012,-.007288,0.0*
1,1,.006,-.007012,-.007288*
20,1,.006,-.007012,-.007288,-.008214,-.006446,0.0*
1,1,.006,-.008214,-.006446*
20,1,.006,-.008214,-.006446,-.009251,-.005409,0.0*
1,1,.006,-.009251,-.005409*
20,1,.006,-.009251,-.005409,-.010093,-.004208,0.0*
1,1,.006,-.010093,-.004208*
20,1,.006,-.010093,-.004208,-.010713,-.002878,0.0*
1,1,.006,-.010713,-.002878*
20,1,.006,-.010713,-.002878,-.011092,-.001461,0.0*
1,1,.006,-.011092,-.001461*
20,1,.006,-.011092,-.001461,-.01122,0.0,0.0*
1,1,.006,-.01122,0.0*
20,1,.006,-.01122,0.0,-.011092,.001461,0.0*
1,1,.006,-.011092,.001461*
20,1,.006,-.011092,.001461,-.010713,.002878,0.0*
1,1,.006,-.010713,.002878*
20,1,.006,-.010713,.002878,-.010093,.004207,0.0*
1,1,.006,-.010093,.004207*
20,1,.006,-.010093,.004207,-.009251,.005409,0.0*
1,1,.006,-.009251,.005409*
20,1,.006,-.009251,.005409,-.008214,.006446,0.0*
1,1,.006,-.008214,.006446*
20,1,.006,-.008214,.006446,-.007013,.007288,0.0*
1,1,.006,-.007013,.007288*
20,1,.006,-.007013,.007288,-.005683,.007908,0.0*
1,1,.006,-.005683,.007908*
20,1,.006,-.005683,.007908,-.004266,.008287,0.0*
1,1,.006,-.004266,.008287*
20,1,.006,-.004266,.008287,-.002805,.008415,0.0*
1,1,.006,-.002805,.008415*
1,1,.006,0.0,-.0042*
20,1,.006,0.0,-.0042,.00099,-.00406,0.0*
1,1,.006,.00099,-.00406*
20,1,.006,.00099,-.00406,.00211,-.00364,0.0*
1,1,.006,.00211,-.00364*
20,1,.006,.00211,-.00364,.00281,-.00294,0.0*
1,1,.006,.00281,-.00294*
20,1,.006,.00281,-.00294,.00309,-.00196,0.0*
1,1,.006,.00309,-.00196*
20,1,.006,.00309,-.00196,.00281,-.00098,0.0*
1,1,.006,.00281,-.00098*
20,1,.006,.00281,-.00098,.00197,-.00014,0.0*
1,1,.006,.00197,-.00014*
20,1,.006,.00197,-.00014,.00071,.00029,0.0*
1,1,.006,.00071,.00029*
20,1,.006,.00071,.00029,-.0007,.00029,0.0*
1,1,.006,-.0007,.00029*
20,1,.006,-.0007,.00029,-.00154,.00057,0.0*
1,1,.006,-.00154,.00057*
20,1,.006,-.00154,.00057,-.00224,.00127,0.0*
1,1,.006,-.00224,.00127*
20,1,.006,-.00224,.00127,-.00252,.00225,0.0*
1,1,.006,-.00252,.00225*
20,1,.006,-.00252,.00225,-.0021,.00323,0.0*
1,1,.006,-.0021,.00323*
20,1,.006,-.0021,.00323,-.00112,.00393,0.0*
1,1,.006,-.00112,.00393*
20,1,.006,-.00112,.00393,0.0,.00421,0.0*
1,1,.006,0.0,.00421*
20,1,.006,0.0,.00421,.00113,.00393,0.0*
1,1,.006,.00113,.00393*
20,1,.006,.00113,.00393,.00211,.00323,0.0*
1,1,.006,.00211,.00323*
20,1,.006,.00211,.00323,.00253,.00225,0.0*
1,1,.006,.00253,.00225*
20,1,.006,.00253,.00225,.00225,.00127,0.0*
1,1,.006,.00225,.00127*
20,1,.006,.00225,.00127,.00155,.00057,0.0*
1,1,.006,.00155,.00057*
20,1,.006,.00155,.00057,.00071,.00029,0.0*
1,1,.006,.00071,.00029*
20,1,.006,.00071,.00029,-.0007,.00029,0.0*
1,1,.006,-.0007,.00029*
20,1,.006,-.0007,.00029,-.00196,-.00014,0.0*
1,1,.006,-.00196,-.00014*
20,1,.006,-.00196,-.00014,-.0028,-.00098,0.0*
1,1,.006,-.0028,-.00098*
20,1,.006,-.0028,-.00098,-.00308,-.00196,0.0*
1,1,.006,-.00308,-.00196*
20,1,.006,-.00308,-.00196,-.0028,-.00294,0.0*
1,1,.006,-.0028,-.00294*
20,1,.006,-.0028,-.00294,-.0021,-.00364,0.0*
1,1,.006,-.0021,-.00364*
20,1,.006,-.0021,-.00364,-.00098,-.00406,0.0*
1,1,.006,-.00098,-.00406*
20,1,.006,-.00098,-.00406,0.0,-.0042,0.0*
1,1,.006,0.0,-.0042*
%
%ADD34MACRO34*%
%ADD36C,.02*%
%ADD37C,.006*%
G75*
%LPD*%
G75*
G54D10*
X8500Y18279D03*
Y28279D03*
Y38279D03*
Y48279D03*
Y58279D03*
Y68279D03*
X13721Y8500D03*
X8500Y13279D03*
Y23279D03*
Y33279D03*
Y43279D03*
Y53279D03*
Y63279D03*
Y78279D03*
Y88279D03*
Y98279D03*
Y108279D03*
Y118279D03*
Y128279D03*
Y73279D03*
Y83279D03*
Y93279D03*
Y103279D03*
Y113279D03*
Y123279D03*
Y133279D03*
Y138279D03*
Y148279D03*
Y158279D03*
Y168279D03*
Y178279D03*
Y188279D03*
Y198279D03*
Y143279D03*
Y153279D03*
Y163279D03*
Y173279D03*
Y183279D03*
Y193279D03*
Y208279D03*
Y218279D03*
Y228279D03*
Y238279D03*
Y248279D03*
Y258279D03*
Y203279D03*
Y213279D03*
Y223279D03*
Y233279D03*
Y243279D03*
Y253279D03*
Y263279D03*
Y268279D03*
Y278279D03*
Y288279D03*
Y298279D03*
Y308279D03*
Y318279D03*
Y328279D03*
Y273279D03*
Y283279D03*
Y293279D03*
Y303279D03*
Y313279D03*
Y323279D03*
Y338279D03*
Y348279D03*
Y358279D03*
Y368279D03*
Y378279D03*
Y388279D03*
Y333279D03*
Y343279D03*
Y353279D03*
Y363279D03*
Y373279D03*
Y383279D03*
Y393279D03*
Y398279D03*
Y408279D03*
Y418279D03*
Y428279D03*
Y438279D03*
Y448279D03*
Y458279D03*
Y403279D03*
Y413279D03*
Y423279D03*
Y433279D03*
Y443279D03*
Y453279D03*
Y468279D03*
Y478279D03*
Y488279D03*
Y498279D03*
Y508279D03*
Y518279D03*
Y528279D03*
Y463279D03*
Y473279D03*
Y483279D03*
Y493279D03*
Y503279D03*
Y513279D03*
Y523279D03*
Y538279D03*
Y548279D03*
Y558279D03*
Y568279D03*
Y578279D03*
Y588279D03*
Y533279D03*
Y543279D03*
Y553279D03*
Y563279D03*
Y573279D03*
Y583279D03*
Y593279D03*
Y598279D03*
Y608279D03*
Y618279D03*
Y628279D03*
Y638279D03*
Y648279D03*
Y658279D03*
Y603279D03*
Y613279D03*
Y623279D03*
Y633279D03*
Y643279D03*
Y653279D03*
Y668279D03*
Y678279D03*
Y688279D03*
Y698279D03*
Y708279D03*
Y718279D03*
Y663279D03*
Y673279D03*
Y683279D03*
Y693279D03*
Y703279D03*
Y713279D03*
X8892Y723187D03*
X11090Y727806D03*
X13500Y732400D03*
X78721Y8500D03*
X68721D03*
X58721D03*
X48721D03*
X38721D03*
X28721D03*
X18721D03*
X73721D03*
X53721D03*
X43721D03*
X33721D03*
X23721D03*
X63721D03*
X75534Y625175D03*
X75300Y679300D03*
Y674300D03*
X78370Y724300D03*
Y719500D03*
X28100Y755600D03*
X33100D03*
X69057Y755280D03*
X74057D03*
X20300Y746200D03*
X15800Y736900D03*
X18100Y741500D03*
X22600Y750800D03*
X79057Y755280D03*
X108721Y8500D03*
X98721D03*
X88721D03*
X112197Y65406D03*
Y60406D03*
Y55406D03*
X103721Y8500D03*
X93721D03*
X83721D03*
X112197Y75406D03*
Y85406D03*
Y95406D03*
Y105406D03*
Y115406D03*
Y120406D03*
Y110406D03*
Y100406D03*
Y90406D03*
Y80406D03*
Y70406D03*
Y145406D03*
Y195406D03*
Y185406D03*
Y175406D03*
Y165406D03*
Y155406D03*
Y200406D03*
Y190406D03*
Y180406D03*
Y170406D03*
Y160406D03*
Y150406D03*
Y265406D03*
Y255406D03*
Y245406D03*
Y235406D03*
Y225406D03*
Y215406D03*
Y205406D03*
Y260406D03*
Y250406D03*
Y240406D03*
Y230406D03*
Y220406D03*
Y210406D03*
Y325406D03*
Y315406D03*
Y305406D03*
Y295406D03*
Y285406D03*
Y275406D03*
Y330406D03*
Y320406D03*
Y310406D03*
Y300406D03*
Y290406D03*
Y280406D03*
Y270406D03*
Y390406D03*
Y380406D03*
Y370406D03*
Y360406D03*
Y350406D03*
Y395406D03*
Y385406D03*
Y375406D03*
Y365406D03*
Y355406D03*
Y345406D03*
Y335406D03*
Y340406D03*
Y420406D03*
Y410406D03*
Y400406D03*
Y425406D03*
Y415406D03*
Y405406D03*
X103600Y637800D03*
X103500Y645500D03*
Y650535D03*
X80334Y625175D03*
X99600Y673500D03*
Y678500D03*
X86500Y703100D03*
X86600Y708300D03*
X96800Y662000D03*
X90200Y667100D03*
X85400D03*
X99600Y683500D03*
X81300Y675100D03*
Y680100D03*
X134223Y691027D03*
X83170Y724300D03*
Y719500D03*
X122435Y666782D03*
Y661982D03*
X144057Y755280D03*
X134057D03*
X124057D03*
X114057D03*
X104057D03*
X94057D03*
X84057D03*
X89057D03*
X99057D03*
X109057D03*
X119057D03*
X129057D03*
X139057D03*
X91700Y744800D03*
X96500D03*
X101300D03*
X106100D03*
X110900D03*
X115700D03*
X120500D03*
X125300D03*
X208300Y704985D03*
X203500D03*
X198700D03*
X193900D03*
X155400Y717700D03*
X204057Y755280D03*
X194057D03*
X184057D03*
X174057D03*
X164057D03*
X154057D03*
X149057D03*
X159057D03*
X169057D03*
X179057D03*
X189057D03*
X199057D03*
X209057D03*
X222700Y704985D03*
X217900D03*
X213100D03*
X249500Y719500D03*
Y724300D03*
X274057Y755280D03*
X264057D03*
X254057D03*
X244057D03*
X234057D03*
X224057D03*
X214057D03*
X219057D03*
X229057D03*
X239057D03*
X249057D03*
X259057D03*
X269057D03*
X249500Y729100D03*
Y733900D03*
Y738700D03*
X315120Y8500D03*
X310120D03*
X305120D03*
X300120D03*
X296020Y9420D03*
Y14420D03*
Y19420D03*
Y24420D03*
Y29420D03*
X321382Y197574D03*
X296282Y189224D03*
Y184424D03*
X301082D03*
Y189224D03*
X335132Y195874D03*
X305862Y210014D03*
X334882Y215874D03*
Y220874D03*
X321382Y202374D03*
X335132Y205974D03*
X335200Y640100D03*
X330400D03*
X335000Y615400D03*
X335300Y609800D03*
X335000Y621200D03*
X325600Y640100D03*
X322586Y653754D03*
X317786D03*
X312986D03*
X308186D03*
X330200Y709300D03*
X334650Y689700D03*
X335350Y684650D03*
X315520Y711720D03*
X325700Y711600D03*
X320320Y711720D03*
X305500Y721000D03*
X310500D03*
X304150Y674700D03*
X299350D03*
X334057Y755280D03*
X324057D03*
X314057D03*
X304057D03*
X294057D03*
X284057D03*
X279057D03*
X289057D03*
X299057D03*
X309057D03*
X319057D03*
X329057D03*
X339057D03*
X305500Y726000D03*
X310500D03*
X381638Y755280D03*
X384809Y752321D03*
X387045Y747849D03*
X389281Y743376D03*
X391517Y738904D03*
X393753Y734432D03*
X395989Y729960D03*
X398225Y725488D03*
X344057Y755280D03*
X521634Y38901D03*
Y34101D03*
X516834Y38901D03*
Y34101D03*
X526434Y43701D03*
X521634D03*
X516834D03*
X520000Y63400D03*
X515200Y66440D03*
X520585Y68348D03*
X536794Y77373D03*
X531664Y78463D03*
X515915Y80576D03*
X520310Y76700D03*
X508668Y79607D03*
X503550Y79500D03*
X511100Y75060D03*
X506100D03*
X511100Y70060D03*
X525200Y71440D03*
X516628Y71806D03*
X600700Y35700D03*
X595500Y35600D03*
X595700Y29800D03*
X600900Y29700D03*
X576610Y388416D03*
Y393416D03*
X576512Y369625D03*
Y364825D03*
X581312Y369625D03*
Y364825D03*
X576610Y398416D03*
Y403416D03*
Y408416D03*
Y413416D03*
Y418416D03*
Y423416D03*
Y428416D03*
Y433416D03*
Y438416D03*
Y443416D03*
Y448416D03*
Y453416D03*
Y458416D03*
Y463416D03*
Y468416D03*
Y473416D03*
Y478416D03*
Y483416D03*
Y488416D03*
Y493416D03*
Y498416D03*
Y503416D03*
Y508416D03*
Y513416D03*
Y518416D03*
Y523416D03*
Y528416D03*
Y533416D03*
Y538416D03*
Y543416D03*
Y548416D03*
Y553416D03*
Y558416D03*
Y563416D03*
Y568416D03*
Y573416D03*
Y578416D03*
Y583416D03*
Y588416D03*
Y593416D03*
Y598416D03*
Y603416D03*
Y608416D03*
Y613416D03*
Y618416D03*
Y623416D03*
Y628416D03*
Y633416D03*
Y638416D03*
Y643416D03*
Y648416D03*
Y653416D03*
Y658416D03*
Y663416D03*
Y668416D03*
Y673416D03*
Y678416D03*
Y683416D03*
Y688416D03*
Y693416D03*
Y698416D03*
Y703416D03*
Y708416D03*
Y713416D03*
Y718416D03*
X577063Y723309D03*
X579299Y727781D03*
X581535Y732253D03*
X583771Y736725D03*
X586007Y741198D03*
X588243Y745670D03*
X590479Y750142D03*
X592715Y754614D03*
X609200Y330400D03*
X658000Y431500D03*
Y409000D03*
Y414000D03*
Y426000D03*
Y420500D03*
X642700Y454400D03*
X642500Y449100D03*
X642600Y459500D03*
X610000Y467500D03*
X609000Y473500D03*
Y478500D03*
Y483500D03*
X645200Y521900D03*
X650400Y517600D03*
X656400Y517500D03*
X661500Y517600D03*
X621600Y486619D03*
X626958Y486419D03*
X642500Y464700D03*
X629500Y482500D03*
Y477000D03*
Y471500D03*
X635000Y482500D03*
Y476500D03*
Y471000D03*
X615500Y529800D03*
X616710Y534500D03*
X657000Y555000D03*
X662000D03*
X661887Y560010D03*
X656887D03*
X645300Y655200D03*
Y650400D03*
Y645600D03*
Y640800D03*
X655000Y705000D03*
Y700200D03*
Y695400D03*
Y690600D03*
X645300Y684000D03*
Y679200D03*
Y674400D03*
Y669600D03*
Y664800D03*
Y660000D03*
X655000Y685800D03*
X659722Y755280D03*
X649722D03*
X639722D03*
X634722D03*
X644722D03*
X654722D03*
X664722D03*
X708483Y311988D03*
X713283D03*
X723900Y326350D03*
X718940Y326270D03*
X714900Y453600D03*
X715200Y459600D03*
X706700Y413900D03*
X710200Y417400D03*
Y422900D03*
Y427900D03*
X698700Y417600D03*
Y423100D03*
Y428100D03*
X676000Y431000D03*
X671000D03*
Y421000D03*
X676000D03*
X671000Y426000D03*
X676000D03*
X715200Y465000D03*
X689500Y518500D03*
Y524000D03*
X694738Y523940D03*
X694690Y519034D03*
X670400Y565500D03*
Y560700D03*
Y555900D03*
Y551100D03*
Y546300D03*
Y541500D03*
Y536700D03*
X687015Y658100D03*
Y653300D03*
Y648500D03*
Y643700D03*
Y682100D03*
X673950Y686104D03*
Y691104D03*
Y696104D03*
Y701104D03*
Y706104D03*
X687015Y677300D03*
Y672500D03*
Y667700D03*
Y662900D03*
X729722Y755280D03*
X719722D03*
X709722D03*
X699722D03*
X689722D03*
X679722D03*
X669722D03*
X674722D03*
X684722D03*
X694722D03*
X704722D03*
X714722D03*
X724722D03*
X734722D03*
X780100Y8500D03*
X775100D03*
X770100D03*
X765100D03*
X760100D03*
X755100D03*
X750100D03*
X745100D03*
X787895D03*
X797895D03*
X792895D03*
X754000Y172700D03*
Y177500D03*
X798359Y351659D03*
X795193Y355540D03*
X791786Y359001D03*
X735484Y429378D03*
Y434178D03*
Y462978D03*
Y458178D03*
Y453378D03*
Y448578D03*
Y443778D03*
Y438978D03*
X798000Y459300D03*
X740300Y427100D03*
Y431900D03*
X751100Y405400D03*
X755900D03*
X760700D03*
X765500D03*
X770300D03*
X775100D03*
X740300Y446300D03*
Y441500D03*
Y436700D03*
X790600Y458000D03*
X781000D03*
X785800D03*
X776200D03*
X789500Y405400D03*
X784700D03*
X779900D03*
X750000Y427100D03*
X754800D03*
X783800Y436000D03*
X779000D03*
X793400D03*
X788600D03*
X788400Y427100D03*
X783600D03*
X778800D03*
X774200Y436000D03*
X774000Y427100D03*
X769200D03*
X764400D03*
X759600D03*
X735484Y467778D03*
X799722Y755280D03*
X789722D03*
X779722D03*
X769722D03*
X759722D03*
X749722D03*
X739722D03*
X744722D03*
X754722D03*
X764722D03*
X774722D03*
X784722D03*
X794722D03*
X807895Y8500D03*
X817895D03*
X827895D03*
X837895D03*
X847895D03*
X857895D03*
X862895D03*
X852895D03*
X842895D03*
X832895D03*
X822895D03*
X812895D03*
X802895D03*
X842600Y339400D03*
X841100Y332300D03*
X826993Y358840D03*
X821502Y358356D03*
X827145Y363638D03*
X821653Y363488D03*
X826900Y332500D03*
X825300Y339900D03*
X825100Y347300D03*
X828100Y352900D03*
X809792Y379122D03*
X814592D03*
X809792Y374322D03*
X814592D03*
X842900Y347200D03*
X840800Y352800D03*
X828000Y459300D03*
X823200D03*
X832800D03*
X818400D03*
X807600D03*
X802800D03*
X812400D03*
X864727Y398458D03*
X804300Y436500D03*
X813900D03*
X809100D03*
X818700D03*
X823500D03*
X830100Y501500D03*
X839700D03*
X834900D03*
X827000Y516000D03*
X832000D03*
Y521000D03*
X827000D03*
X843900Y464000D03*
X848700Y465200D03*
Y470600D03*
X849722Y755280D03*
X839722D03*
X829722D03*
X819722D03*
X809722D03*
X804722D03*
X814722D03*
X824722D03*
X834722D03*
X844722D03*
X854722D03*
X867895Y8500D03*
X877895D03*
X887895D03*
X897895D03*
X907895D03*
X916697Y19698D03*
Y29698D03*
Y39698D03*
Y49698D03*
Y59698D03*
Y69698D03*
Y64698D03*
Y54698D03*
Y44698D03*
Y34698D03*
Y24698D03*
Y14698D03*
X912895Y8500D03*
X902895D03*
X892895D03*
X882895D03*
X872895D03*
X916697Y79698D03*
Y89698D03*
Y99698D03*
Y109698D03*
Y119698D03*
Y129698D03*
Y134698D03*
Y124698D03*
Y114698D03*
Y104698D03*
Y94698D03*
Y84698D03*
Y74698D03*
Y139698D03*
Y149698D03*
Y159698D03*
Y169698D03*
Y179698D03*
Y189698D03*
Y199698D03*
Y194698D03*
Y184698D03*
Y174698D03*
Y164698D03*
Y154698D03*
Y144698D03*
Y209698D03*
Y219698D03*
Y229698D03*
Y239698D03*
Y249698D03*
Y259698D03*
Y264698D03*
Y254698D03*
Y244698D03*
Y234698D03*
Y224698D03*
Y214698D03*
Y204698D03*
Y269698D03*
Y279698D03*
Y289698D03*
Y299698D03*
Y309698D03*
Y319698D03*
Y329698D03*
Y324698D03*
Y314698D03*
Y304698D03*
Y294698D03*
Y284698D03*
Y274698D03*
Y339698D03*
Y349698D03*
Y359698D03*
Y369698D03*
Y379698D03*
Y389698D03*
Y394698D03*
Y384698D03*
Y374698D03*
Y364698D03*
Y354698D03*
Y344698D03*
Y334698D03*
X881147Y394517D03*
X916697Y399698D03*
Y409698D03*
Y419698D03*
Y429698D03*
Y439698D03*
Y449698D03*
Y459698D03*
Y454698D03*
Y444698D03*
Y434698D03*
Y424698D03*
Y414698D03*
Y404698D03*
X874727Y398458D03*
X869727D03*
X880887Y399474D03*
X916697Y469698D03*
Y479698D03*
Y489698D03*
Y499698D03*
Y509698D03*
Y519698D03*
Y524698D03*
Y514698D03*
Y504698D03*
Y494698D03*
Y484698D03*
Y474698D03*
Y464698D03*
Y529698D03*
Y539698D03*
Y549698D03*
Y559698D03*
Y569698D03*
Y579698D03*
Y589698D03*
Y584698D03*
Y574698D03*
Y564698D03*
Y554698D03*
Y544698D03*
Y534698D03*
Y599698D03*
Y609698D03*
Y619698D03*
Y629698D03*
Y639698D03*
Y649698D03*
Y659698D03*
Y654698D03*
Y644698D03*
Y634698D03*
Y624698D03*
Y614698D03*
Y604698D03*
Y594698D03*
Y669698D03*
Y679698D03*
Y689698D03*
Y699698D03*
Y709698D03*
Y719698D03*
Y714698D03*
Y704698D03*
Y694698D03*
Y684698D03*
Y674698D03*
Y664698D03*
X914700Y726100D03*
X912436Y730603D03*
X910200Y735300D03*
X907564Y739747D03*
X905500Y744400D03*
X903192Y748791D03*
X900800Y753700D03*
X894722Y755280D03*
X1129450Y646150D03*
G54D11*
X80708Y44292D03*
X61024Y34449D03*
X33464D03*
X56102Y24606D03*
X38386D03*
X108268Y44292D03*
X103346Y34449D03*
X85630D03*
X590300Y574400D03*
X600300D03*
X610300D03*
X1129450Y533750D03*
G54D20*
X197243Y589764D03*
X203542Y592913D03*
X168898Y548819D03*
X172000Y577150D03*
X184645Y589764D03*
X175197D03*
X209842Y583464D03*
X187795Y570866D03*
X184646Y577165D03*
X187795D03*
X190945D03*
X190944Y574016D03*
X190945Y570866D03*
X187795Y574016D03*
X184646D03*
Y570866D03*
X187795Y564567D03*
X194094Y567716D03*
X190945D03*
X187795D03*
X184646D03*
X206692Y592913D03*
X184645Y539370D03*
X194094D03*
X203542Y545671D03*
X197243Y539371D03*
X206692Y555120D03*
X194093D03*
X184646D03*
X153149Y536221D03*
X165748Y558268D03*
X172048Y555120D03*
X156297Y558267D03*
X172048Y589764D03*
X168898D03*
Y561417D03*
Y570866D03*
X156299Y586614D03*
Y580315D03*
X159449Y567717D03*
X156299Y570866D03*
X197243Y592913D03*
X200393Y589764D03*
X187794Y586614D03*
X203542Y589764D03*
X187795Y592914D03*
X165748Y583464D03*
X209841Y574016D03*
X206692D03*
X165745Y564567D03*
X168895D03*
X159449Y561417D03*
X165748D03*
X172047D03*
X162598Y558268D03*
X168898D03*
X165748Y555118D03*
X159449D03*
X168898Y567717D03*
X159449Y570866D03*
X168898Y583464D03*
Y577165D03*
X159449Y586614D03*
X162598Y580315D03*
Y586614D03*
X165748D03*
X168898D03*
X159449Y577165D03*
X156299D03*
X168898Y580315D03*
X159449D03*
X162598Y577165D03*
X165748Y580315D03*
X162598Y583464D03*
X165748Y570866D03*
Y567717D03*
X162598D03*
X172047Y570866D03*
X162597Y555118D03*
X197243Y551970D03*
X194093D03*
X200395Y555120D03*
X181497Y551970D03*
Y589764D03*
X187795Y555120D03*
X206692Y564569D03*
Y561419D03*
Y558269D03*
Y567718D03*
X203543Y574017D03*
X206692Y583465D03*
X194093Y586614D03*
X178347Y551970D03*
X175197D03*
Y558268D03*
X178347Y589764D03*
X190945Y542519D03*
X172047Y545669D03*
Y551970D03*
X159449Y545671D03*
X162599Y545669D03*
X165749D03*
X184646Y548821D03*
Y545671D03*
X209842Y567717D03*
X184645Y542519D03*
X206692Y542521D03*
X209841Y577165D03*
X159449Y542521D03*
X156299Y545671D03*
X168898Y592913D03*
X181497Y545671D03*
X209842Y545669D03*
X165749Y548819D03*
X175197Y545671D03*
X162599Y542519D03*
X168898D03*
X156299Y542521D03*
X181496Y542520D03*
X159449Y548821D03*
X206692Y589763D03*
X172047Y548819D03*
X168898Y551969D03*
X162599Y548821D03*
X194093Y589764D03*
Y592913D03*
X162598Y561417D03*
X168898Y555119D03*
X181497Y548821D03*
X178346Y545670D03*
X206692Y586614D03*
X209842Y586613D03*
X209841Y592913D03*
X162595Y564567D03*
X162598Y570866D03*
X203542Y548821D03*
Y586614D03*
Y580315D03*
X178344Y577166D03*
X178346Y586615D03*
X181497Y586614D03*
X178347Y574018D03*
Y570868D03*
X190944Y586614D03*
X200394Y570866D03*
Y574016D03*
X203543Y561418D03*
Y564568D03*
X165748Y551968D03*
X159448D03*
X178346Y555119D03*
X178347Y564569D03*
X197245Y555118D03*
X190944D03*
X181497Y555120D03*
X172048Y564569D03*
X172047Y567717D03*
X175298Y577266D03*
X209842Y558268D03*
X190944Y589764D03*
Y592913D03*
X197244Y586615D03*
X200393Y586614D03*
X194094Y542519D03*
X209842Y564567D03*
X200393Y548819D03*
X209842Y561417D03*
Y589763D03*
X206692Y580315D03*
X209841D03*
X200393Y545669D03*
X206692Y545671D03*
X200393Y592913D03*
X159448Y589764D03*
Y592913D03*
X162598Y589764D03*
X165748D03*
Y592913D03*
X165749Y542519D03*
X175197Y592913D03*
X172048D03*
X209842Y555119D03*
Y551969D03*
X181497Y592913D03*
X197244Y545669D03*
X194094Y548820D03*
X209842Y548819D03*
X175197Y548821D03*
X168898Y545669D03*
X156300Y539371D03*
X194094Y545669D03*
X197244Y542520D03*
X194094Y602362D03*
X206692Y596063D03*
X194093D03*
X203605Y605450D03*
X200393Y596063D03*
X187795Y602363D03*
X153149Y605513D03*
X209841Y596063D03*
X190945Y599213D03*
X190944Y596063D03*
X187796Y599212D03*
X184645Y599213D03*
X159448Y596063D03*
X168898D03*
X203542Y602362D03*
Y599213D03*
X206692Y602362D03*
X203542Y596063D03*
X194094Y599213D03*
X162598Y596063D03*
X165748Y599213D03*
X168898D03*
X162598D03*
X159448D03*
X172048Y596063D03*
X178346Y596064D03*
X178347Y599213D03*
X181496Y596062D03*
X209841Y599212D03*
X206692Y599213D03*
X165748Y596063D03*
X175197D03*
Y599213D03*
X172048D03*
X219800Y445700D03*
X213874Y445226D03*
X216141Y580315D03*
X212992Y586614D03*
X216141Y577165D03*
X212991Y567718D03*
X216141Y583465D03*
Y586614D03*
Y564569D03*
X212992Y561417D03*
X216141Y567718D03*
X219293Y567717D03*
X212992Y580315D03*
X212991Y577165D03*
Y574016D03*
X216141D03*
Y561419D03*
X212991Y583465D03*
Y542519D03*
X212992Y589764D03*
Y555119D03*
Y558268D03*
X216142Y548820D03*
X216141Y555120D03*
Y558269D03*
X222441Y548820D03*
X219291D03*
X212992Y551969D03*
X216141Y551970D03*
X212992Y548819D03*
X216141Y589762D03*
X212993Y592912D03*
X212992Y564567D03*
Y545669D03*
X216142D03*
X222440Y605512D03*
X212992Y602363D03*
X212991Y599212D03*
X216141D03*
X762173Y294089D03*
X781088Y294094D03*
X771653Y294093D03*
X777952Y290944D03*
X777989Y294093D03*
X774802Y290944D03*
X774835Y294088D03*
X768503Y290944D03*
X768498Y294124D03*
X765353Y290944D03*
X765325Y294102D03*
X759054Y290944D03*
X759055Y294094D03*
X755905Y290944D03*
Y294093D03*
X787401Y290944D03*
X787408Y294074D03*
X784251Y290944D03*
X784258Y294064D03*
X1129450Y814750D03*
G54D12*
X18700Y54650D03*
X209189Y37075D03*
Y383483D03*
X489331Y245605D03*
Y698924D03*
X901000Y21400D03*
X902500Y676000D03*
X1129450Y308950D03*
G54D30*
X488838Y164744D03*
X1129450Y280850D03*
G54D21*
X163189Y669291D03*
X1129450Y421350D03*
G54D31*
X564803Y24409D03*
X574803D03*
X584803D03*
X753780D03*
X763780D03*
X773780D03*
X801024D03*
X811024D03*
X821024D03*
X1129450Y561850D03*
G54D22*
X201801Y684252D03*
X225601D03*
X1129450Y393250D03*
G54D13*
X77780Y61790D03*
X73760Y67930D03*
X56960Y58900D03*
X54050Y63260D03*
X43510Y57810D03*
X29890Y54070D03*
X49460Y63690D03*
X68730Y67930D03*
X38590Y55260D03*
X30270Y48330D03*
X31100Y458733D03*
X26576Y457406D03*
X34132Y521245D03*
X34175Y526969D03*
X64277Y502177D03*
X75399Y502179D03*
X69904Y502077D03*
X41250Y494600D03*
X53524Y521269D03*
Y526995D03*
X75405Y521695D03*
X69778D03*
X64151D03*
X49600Y496050D03*
X55300Y495600D03*
X62276Y550493D03*
X28800Y549474D03*
X29158Y543855D03*
X29058Y538228D03*
X28782Y555119D03*
X29165Y532612D03*
X33697Y560866D03*
X37660Y566400D03*
X42597Y571789D03*
X71002Y577013D03*
X67853Y573865D03*
X75197Y572437D03*
X64701Y570716D03*
Y564416D03*
X67853Y558117D03*
X61100Y546700D03*
X64400Y539000D03*
X67852Y586463D03*
Y583313D03*
X74151Y545516D03*
X74498Y551757D03*
X71002Y539219D03*
X74076Y535966D03*
X75508Y542198D03*
X71002Y542368D03*
X67852Y539219D03*
X71002Y545518D03*
Y558117D03*
X74152Y567565D03*
X71002D03*
Y564396D03*
X74152Y580163D03*
Y577013D03*
X71002Y561266D03*
X67853Y564416D03*
X75066Y563235D03*
X71002Y554967D03*
X67853D03*
X78276Y545566D03*
X67853Y542368D03*
X71002Y548668D03*
X52408Y543876D03*
X64701Y542366D03*
X52603Y549526D03*
X52485Y555153D03*
X53300Y560879D03*
X67853Y570715D03*
X74152Y583312D03*
X64703Y586463D03*
X63456Y555041D03*
X64701Y567566D03*
Y561266D03*
X67853D03*
Y577015D03*
X53524Y532622D03*
X52613Y538242D03*
X53302Y567317D03*
X59200Y582200D03*
X64884Y650984D03*
X38550Y617950D03*
X50700Y664000D03*
X50800Y667900D03*
X40309Y660700D03*
X71850Y698900D03*
X47150Y665500D03*
X76100Y697100D03*
X97600Y54810D03*
X84610Y64470D03*
X98770Y60860D03*
X89070Y62600D03*
X114390Y453185D03*
X102250Y455000D03*
X108300Y435900D03*
X118108Y453159D03*
X121826Y453156D03*
X128968Y452741D03*
X125353Y452385D03*
X132109Y451199D03*
X136021Y451394D03*
X127812Y445066D03*
X107100Y497300D03*
X97926Y502300D03*
X86699D03*
X81094Y502166D03*
X138900Y525999D03*
X135012Y510200D03*
X119400Y511500D03*
X132100Y493000D03*
X133152Y484074D03*
X105350Y511850D03*
X114070Y481948D03*
X117200Y495200D03*
X105920Y477098D03*
X141980Y508590D03*
X97637Y492891D03*
X118900Y522000D03*
X138000Y485900D03*
X116500Y477000D03*
X144500Y489500D03*
X92286Y521695D03*
X81032D03*
X86659D03*
X97913D03*
X114500Y490000D03*
X137050Y476346D03*
X132774Y497000D03*
X89899Y558115D03*
X86750Y573864D03*
X89899D03*
X86750Y567565D03*
X89899Y564415D03*
X106272Y547370D03*
X94473Y547093D03*
X89901Y587466D03*
X93048Y577014D03*
X108371Y577258D03*
X136990Y535235D03*
X86750Y542368D03*
X126337Y554085D03*
X130311Y546700D03*
X81276Y548766D03*
X119605Y548705D03*
X86750Y539218D03*
X83600Y545518D03*
X89899D03*
X127300Y543200D03*
X89899Y539218D03*
X117200Y546300D03*
X83600Y539219D03*
X86750Y545518D03*
X122600Y557480D03*
X86750Y554965D03*
X130607Y569636D03*
X86750Y558115D03*
X126347Y569556D03*
X83600Y551817D03*
X117400Y567650D03*
X83600Y573865D03*
X86750Y586463D03*
Y583313D03*
X83601Y580164D03*
X89899Y577014D03*
X86750D03*
X83600Y564415D03*
X86750D03*
X83600Y561265D03*
X96570Y581730D03*
X86750Y551815D03*
X123300Y530300D03*
X133800Y528500D03*
X123200Y534600D03*
X143500Y529000D03*
X93744Y542019D03*
X133554Y537374D03*
X93051Y587466D03*
X83600Y567565D03*
X93049Y573864D03*
X89899Y567565D03*
X93048Y580164D03*
X89899Y561265D03*
X86750D03*
X94720Y557158D03*
X92600Y535623D03*
X96371Y534124D03*
X101400Y606300D03*
X97800D03*
X137210Y622030D03*
X134030Y620760D03*
X130630Y620900D03*
X101500Y597000D03*
X85500Y628500D03*
X122750Y616950D03*
X122000Y628700D03*
X144800Y657900D03*
X136100Y656300D03*
X125100Y656700D03*
X123370Y606700D03*
X119600D03*
X118500Y638100D03*
X140700Y657700D03*
X130800Y656100D03*
X127401Y606930D03*
X93053Y606734D03*
X142447Y611714D03*
X119000Y633200D03*
X120500Y651800D03*
X134650Y612900D03*
X144750Y606350D03*
X98200Y616900D03*
X129800Y630700D03*
X117050Y602000D03*
X116500Y621000D03*
X130800Y606700D03*
X138500Y637900D03*
X130500Y638600D03*
X134700D03*
X111300Y705500D03*
X107100Y679600D03*
X106879Y707245D03*
X125376Y701124D03*
X106355Y710745D03*
X106635Y701465D03*
X87683Y698924D03*
X84600Y688000D03*
X119849Y709715D03*
X146301Y460200D03*
X186602Y459767D03*
X197085Y459899D03*
X190278Y459865D03*
X193686Y459799D03*
X172200Y460100D03*
X157496Y461248D03*
X166600Y509800D03*
X166700Y499800D03*
X146263Y468562D03*
X203307Y506400D03*
X179000Y499800D03*
X203500Y513500D03*
X186735Y463748D03*
X207500Y503000D03*
X191418Y509981D03*
X170870Y492270D03*
X158000Y480700D03*
X146143Y481057D03*
X175100Y477000D03*
X208370Y491570D03*
X183100Y499800D03*
X170838Y481762D03*
X146300Y502600D03*
X146112Y509412D03*
X158100Y493000D03*
X158400Y513600D03*
X155001Y513707D03*
X182874Y513591D03*
X178869Y513593D03*
X174900Y499800D03*
X166600Y513600D03*
X170700D03*
X172370Y463798D03*
X187000Y468000D03*
X146293Y464338D03*
X146193Y476938D03*
X146293Y472738D03*
X186600Y477700D03*
X187000Y499500D03*
X146500Y492500D03*
X145400Y524046D03*
X176100Y473200D03*
X174700Y513900D03*
X182300Y509600D03*
X184780Y526990D03*
X187167Y513167D03*
X191100Y513367D03*
X154500Y487000D03*
X178869Y509793D03*
X209800Y478500D03*
X158290Y502380D03*
X205516Y467968D03*
X170700Y509800D03*
X170900Y500000D03*
X209256Y467946D03*
X172100Y467300D03*
X176800Y492200D03*
X175805Y524073D03*
X206180Y509524D03*
X191100Y526000D03*
X195149Y513751D03*
X150500Y493000D03*
X190950Y482100D03*
X200100Y491700D03*
X146216Y486045D03*
X196243Y486782D03*
X159480Y506590D03*
X155540Y506510D03*
X195300Y498900D03*
X150162Y525937D03*
X148527Y519491D03*
X191725Y523074D03*
X195300Y529400D03*
X148409Y575672D03*
X144876Y590854D03*
X148409Y579353D03*
X144876Y587173D03*
X175100Y529100D03*
X203610Y529397D03*
X168390Y532060D03*
X184830Y529960D03*
X149419Y535654D03*
X191200Y529400D03*
X199400D03*
X208000Y529300D03*
X149242Y531080D03*
X152584Y532922D03*
X152415Y540014D03*
X171020Y611020D03*
X200610Y639611D03*
X207900Y645600D03*
X169000Y640300D03*
X184967Y643983D03*
X200560Y635100D03*
X170940Y614400D03*
X191110Y611050D03*
X191370Y608190D03*
X208700Y625149D03*
X200879Y614739D03*
X145900Y641300D03*
X164800Y640200D03*
X173000Y640400D03*
X193610Y640040D03*
X189500Y639700D03*
X178140Y630330D03*
X196249Y630091D03*
X199400Y628646D03*
X163200Y610070D03*
X160420Y610170D03*
X184050Y629500D03*
X181176Y627600D03*
X209093Y615849D03*
X166690Y615060D03*
X166600Y617850D03*
X195900Y649350D03*
X203400Y649600D03*
X180700Y640460D03*
X204800Y617440D03*
X204642Y621140D03*
X177300Y626800D03*
X152700Y640800D03*
X161000Y634300D03*
X157200Y634200D03*
X196855Y698355D03*
X151130Y703440D03*
X148249Y695765D03*
X191766Y679920D03*
X202800Y660900D03*
X189000Y659900D03*
X206700Y695400D03*
X162100Y711215D03*
X151949Y691715D03*
X175233Y704382D03*
X163349Y702715D03*
X163260Y706988D03*
X169070Y696220D03*
X159519Y694455D03*
X193500Y663000D03*
X200400Y694700D03*
X196900Y661350D03*
X206300Y661100D03*
X181300Y679100D03*
X185100Y705600D03*
X184800Y709300D03*
X190200Y671000D03*
X187500Y673100D03*
X272000Y461800D03*
X268350Y461950D03*
X275100Y460300D03*
X259000Y453900D03*
X251700Y443600D03*
X268900Y445150D03*
X244700Y451200D03*
X236100Y445100D03*
X239300Y443800D03*
X243000D03*
X247900Y445300D03*
X260600Y442600D03*
X250500Y451300D03*
X224500Y445600D03*
X254900Y453900D03*
X232200Y445600D03*
X275500Y466200D03*
X211700Y513500D03*
X220100Y513400D03*
X211196Y487762D03*
X222600Y503500D03*
X246000Y516670D03*
X275700Y490300D03*
X244900Y527300D03*
X228150Y525750D03*
X275400Y470300D03*
X213100Y476300D03*
X261200Y525400D03*
X242500Y523500D03*
X213100Y472900D03*
X275200Y474500D03*
X258100Y516400D03*
X227500Y512200D03*
X265148Y524595D03*
X249050Y527150D03*
X258381Y509498D03*
X225914Y523051D03*
X231800Y512100D03*
X223600Y512400D03*
X213359Y480489D03*
X238400Y511300D03*
X265274Y509512D03*
X267800Y479900D03*
X222500Y536161D03*
X211500Y529400D03*
X230900Y581600D03*
X229800Y593200D03*
X247400Y589600D03*
X252593Y547650D03*
X261900Y591300D03*
X247100Y582400D03*
X246611Y551511D03*
X246484Y537139D03*
X269900Y567619D03*
X245743Y546963D03*
X270021Y549394D03*
X257000Y548400D03*
X263216Y554697D03*
X254530Y564300D03*
X251446Y553754D03*
X254500Y579500D03*
X273500Y567400D03*
X254300Y586500D03*
X273400Y590902D03*
X231434Y562844D03*
X234300Y582300D03*
X231200Y576800D03*
X231000Y571900D03*
X257300Y537500D03*
X214900Y529400D03*
X234943Y565199D03*
X254600Y567700D03*
X260731Y561264D03*
X260741Y542700D03*
X264333Y528926D03*
X258528Y555161D03*
X259100Y567706D03*
X257000Y571700D03*
X223900Y531200D03*
X228100Y545500D03*
X228800Y542100D03*
X228313Y552169D03*
X262000Y586900D03*
X257851Y580080D03*
X270145Y557526D03*
X261308Y583388D03*
X237100Y590000D03*
X257700Y586400D03*
X261500Y576400D03*
X261600Y580000D03*
X257891Y563786D03*
X257600Y576500D03*
X233607Y557671D03*
X254500Y575070D03*
X261100Y571600D03*
X234800Y572000D03*
X232400Y533200D03*
X248900Y545700D03*
X267957Y537304D03*
X274623Y578896D03*
X271357Y537253D03*
X233036Y550942D03*
X213800Y631200D03*
X212308Y605949D03*
X229796Y610104D03*
X270000Y602400D03*
X255228Y631071D03*
X255648Y626127D03*
X245300Y635700D03*
X254199Y603443D03*
X254600Y597100D03*
X229137Y634881D03*
X266857Y634343D03*
X256001Y612347D03*
X258869Y603050D03*
X266571Y608619D03*
X275470Y608480D03*
X270400Y622870D03*
X264040Y648370D03*
X219200Y647200D03*
X221900Y630800D03*
X218800Y635600D03*
X230900Y649100D03*
X211706Y645349D03*
X247725Y656375D03*
X246500Y601500D03*
X234000Y629576D03*
X218200Y651400D03*
X248450Y609900D03*
X266847Y626253D03*
X229063Y638560D03*
X216600Y658400D03*
X274800Y635000D03*
X222950Y647900D03*
X255570Y616631D03*
X258962Y616384D03*
X236000Y647400D03*
X225900Y630700D03*
X231500Y659100D03*
X228149Y600094D03*
X242710Y604620D03*
X226471Y649129D03*
X243322Y597509D03*
X251314Y598106D03*
X251338Y601506D03*
X258550Y606527D03*
Y610096D03*
X215606Y645806D03*
X229500Y631500D03*
X212900Y619201D03*
X273714Y629870D03*
X266571Y630071D03*
X245100Y647200D03*
X272200Y648550D03*
X221238Y620524D03*
X234205Y598743D03*
X233258Y595693D03*
X232130Y612950D03*
X251900Y609600D03*
X259777Y638873D03*
X242000Y656400D03*
X255733Y622329D03*
X253196Y706062D03*
X261248Y700086D03*
X272050Y711810D03*
X267880Y704920D03*
X262634Y711233D03*
X266400Y675349D03*
X265000Y662574D03*
X247825Y670375D03*
X235100Y679921D03*
X221575Y695400D03*
X242000Y693400D03*
X255050Y675750D03*
X254800Y689400D03*
X269200Y699600D03*
X258423Y711343D03*
X268520Y719420D03*
X270900Y667200D03*
X237509Y674915D03*
X266200Y679400D03*
X268384Y662909D03*
X263700Y723500D03*
X264700Y700000D03*
X214270Y695095D03*
X275300Y668749D03*
X217638Y695562D03*
X235000Y692900D03*
X262323Y716917D03*
X255200Y680950D03*
X239400Y677900D03*
X266300Y692574D03*
X254648Y745463D03*
X311715Y20397D03*
X310353Y62159D03*
X326553Y34687D03*
X340297Y117548D03*
X341484Y110328D03*
X339232Y113960D03*
X338743Y122894D03*
X305700Y197600D03*
X295841Y176793D03*
X323582Y179064D03*
X299107Y177740D03*
X295462Y173414D03*
X304231Y265048D03*
Y261048D03*
X322426Y223731D03*
Y227531D03*
X321197Y254433D03*
X322426Y231331D03*
X321782Y215974D03*
X306446Y247874D03*
X305382Y227474D03*
X305498Y213824D03*
X305703Y202165D03*
X306407Y206057D03*
X335000Y226992D03*
X305782Y230874D03*
X335082Y231574D03*
X322301Y220009D03*
X305782Y217274D03*
X305682Y224074D03*
X305782Y220674D03*
X305454Y244461D03*
X334998Y255520D03*
X305373Y251101D03*
X334998Y259033D03*
X306412Y254339D03*
X335060Y262516D03*
X305882Y234274D03*
X305772Y237673D03*
X321700Y246000D03*
X321600Y250000D03*
X305781Y241076D03*
X334582Y291284D03*
Y287284D03*
Y283784D03*
Y279784D03*
X307567Y331592D03*
Y328092D03*
Y324092D03*
X304267Y322892D03*
Y318892D03*
Y315392D03*
Y311392D03*
X307567Y310292D03*
Y306292D03*
Y302792D03*
Y298792D03*
X304267Y297692D03*
Y293692D03*
Y290192D03*
Y286192D03*
X334582Y330271D03*
X328182Y329174D03*
Y325174D03*
Y321674D03*
Y317674D03*
X334582Y316574D03*
Y312574D03*
Y309074D03*
Y305074D03*
X328182Y303977D03*
Y299977D03*
Y296477D03*
Y292477D03*
X307567Y285092D03*
Y281092D03*
Y277592D03*
Y273592D03*
X304231Y272548D03*
Y268548D03*
X321281Y266486D03*
X321432Y279090D03*
X321882Y291874D03*
Y304374D03*
X321432Y316885D03*
Y329484D03*
X328913Y274414D03*
X334017Y272000D03*
X337808Y288709D03*
X304267Y373292D03*
Y369292D03*
Y365792D03*
Y361792D03*
X307567Y360692D03*
Y356692D03*
Y353192D03*
Y349192D03*
X304267Y348092D03*
Y344092D03*
Y340592D03*
Y336592D03*
X307567Y335592D03*
X328182Y379518D03*
Y375518D03*
Y372018D03*
Y368018D03*
X334582Y366974D03*
Y362974D03*
Y359474D03*
Y355474D03*
Y341771D03*
Y337771D03*
Y334271D03*
X328182Y354371D03*
Y350371D03*
Y346871D03*
Y342871D03*
X321432Y342082D03*
Y354681D03*
X321202Y376887D03*
X321432Y367279D03*
X335982Y390874D03*
X334000Y382700D03*
X303680Y380972D03*
X316900Y384100D03*
X319679Y387121D03*
X314000Y390500D03*
X335800Y379800D03*
X338800Y435100D03*
X281200Y453500D03*
X333850Y458400D03*
X286700Y457500D03*
X323759Y435145D03*
X327159Y435201D03*
X276634Y498311D03*
X307364Y505750D03*
X321976D03*
X329035Y519325D03*
X293793Y521556D03*
X321208Y519411D03*
X325136Y519316D03*
X333922Y527323D03*
X340961Y511600D03*
X298335Y521458D03*
X304800Y512800D03*
X308687Y519193D03*
X302307Y505799D03*
X298907Y505851D03*
X336600Y504500D03*
X336800Y499967D03*
X325400Y505800D03*
X282403Y474500D03*
X282400Y470200D03*
X328200Y511600D03*
X331200Y508900D03*
X299448Y511300D03*
X277603Y479948D03*
X332821Y515415D03*
X280939Y504705D03*
X314400Y505750D03*
X334650Y508900D03*
X300476Y546907D03*
X285800Y549394D03*
X303100Y587000D03*
X292850Y586100D03*
X293271Y557248D03*
X327110Y583660D03*
X316680Y583527D03*
X337899Y587874D03*
X285982Y542502D03*
X310350Y538293D03*
X330860Y551744D03*
X325447Y536109D03*
X325774Y547428D03*
X331700Y587896D03*
X303520Y550085D03*
X296835Y591015D03*
X280646Y557150D03*
X303500Y582200D03*
X333847Y531105D03*
X286195Y530579D03*
X291800Y576708D03*
X337550Y534619D03*
X295824Y578108D03*
X323659Y557310D03*
X334900Y586100D03*
X333512Y553888D03*
X281610Y590260D03*
X324200Y565300D03*
X281490Y586862D03*
X337300Y583000D03*
X336367Y549943D03*
X294107Y560762D03*
X330729Y557268D03*
X327059Y557247D03*
X288309Y566467D03*
X291000Y570810D03*
X277048Y590470D03*
X319529Y562413D03*
X319252Y566509D03*
X285912Y538750D03*
X318736Y549697D03*
X280100Y532100D03*
X322889Y529380D03*
X322843Y533254D03*
X279664Y535473D03*
X328771Y549035D03*
X332808Y547575D03*
X332834Y543993D03*
X341316Y545000D03*
X282000Y583500D03*
X298514Y550184D03*
X293087Y530571D03*
X325687Y551368D03*
X319430Y557486D03*
X276839Y582309D03*
X277441Y539882D03*
X310292Y532128D03*
X339081Y628173D03*
X290300Y636900D03*
X290500Y640600D03*
X331655Y603405D03*
X339822Y609785D03*
X339847Y620281D03*
X305470Y623734D03*
X278546Y633450D03*
X281900Y640900D03*
X317600Y603300D03*
X339266Y658409D03*
X278443Y648857D03*
X284495Y613130D03*
X286700Y622190D03*
X340100Y631417D03*
X339751Y616882D03*
Y613185D03*
X335036Y603039D03*
X338733D03*
X294500Y630600D03*
X298100Y630650D03*
X334700Y644500D03*
X302459Y599531D03*
X306100Y599500D03*
X306231Y602898D03*
X302180Y603084D03*
X335100Y650600D03*
X338100Y635800D03*
X331718Y655832D03*
X329100Y650700D03*
X317689Y599833D03*
X287200Y632600D03*
X290900Y630900D03*
X278769Y700697D03*
X318400Y678400D03*
X325900Y678500D03*
X281400Y708200D03*
X281500Y712200D03*
X279400Y686400D03*
X294804Y695204D03*
X296800Y665081D03*
X311600Y670354D03*
X319600Y670450D03*
X293300Y679700D03*
X321800Y678500D03*
X281000Y678000D03*
X304400Y665100D03*
X316465Y716063D03*
X340500Y711750D03*
X335750Y664700D03*
X288700Y667900D03*
X340100Y718200D03*
X327162Y696776D03*
X282300Y700100D03*
X276800Y697925D03*
X338669Y691580D03*
X339804Y679030D03*
X340403Y699400D03*
X340300Y703100D03*
X336200Y677000D03*
X289700Y678830D03*
X280646Y717540D03*
X276100Y677700D03*
X300100Y670300D03*
X304700Y668500D03*
X298570Y743670D03*
X306470Y743570D03*
X278553Y740020D03*
X291700Y737000D03*
X287620Y737300D03*
X290000Y727000D03*
X313873Y735907D03*
X314100Y739300D03*
X380500Y33500D03*
Y30000D03*
X384000D03*
X381173Y49058D03*
X381156Y54116D03*
X375200Y63400D03*
X370870Y45605D03*
X368059Y57759D03*
X354798Y22452D03*
X375300Y72150D03*
X374844Y87900D03*
X375000Y107300D03*
X393206Y77614D03*
X374844Y76700D03*
X362000Y124000D03*
X386759Y79693D03*
X390456D03*
X342539Y120370D03*
X369253Y88733D03*
X367287Y77118D03*
X381269Y94981D03*
X384666Y93741D03*
X349206Y129948D03*
X390964Y87226D03*
X388700Y89800D03*
X349072Y193574D03*
X400212Y154732D03*
X400351Y165605D03*
X349072Y189774D03*
X371775Y200577D03*
X348082Y186224D03*
X370149Y167337D03*
X370882Y163688D03*
X387202Y164664D03*
X387393Y160859D03*
X404727Y162141D03*
X392102Y175384D03*
X400205Y158209D03*
Y161906D03*
X392458Y171676D03*
X400430Y147190D03*
X362197Y222068D03*
X362722Y237674D03*
X361792Y243154D03*
X372888Y208022D03*
X359882Y203458D03*
X347482Y254774D03*
X341882Y251064D03*
X342885Y276301D03*
X342958Y279701D03*
X383170Y329807D03*
X345582Y380874D03*
X344732Y393882D03*
Y390274D03*
X383285Y347114D03*
X383327Y343379D03*
X396561Y351418D03*
X346600Y375000D03*
X344732Y386874D03*
X365100Y348300D03*
X372491Y378025D03*
X365200Y344400D03*
X378492Y378175D03*
X383030Y352442D03*
X367358Y372531D03*
X367471Y369120D03*
X360100Y453500D03*
X342700Y435200D03*
X350491Y453809D03*
X372000Y452100D03*
X369900Y458700D03*
X387450Y454558D03*
X387396Y458126D03*
X384395Y449114D03*
X374700Y460300D03*
X350400Y459000D03*
X381106Y441241D03*
X350400Y462400D03*
X374650Y456771D03*
X346500Y435200D03*
X364500Y453700D03*
X367400Y461200D03*
X355400Y453800D03*
X357900Y450800D03*
X369000Y512700D03*
X345497Y527644D03*
X355300Y510100D03*
X353300Y521400D03*
X344700Y509000D03*
X368721Y525271D03*
X371900Y481548D03*
X365800Y498300D03*
X357450Y491450D03*
X364500Y525260D03*
X369300Y508700D03*
X344400Y505400D03*
X344500Y500300D03*
X363500Y464700D03*
X372000Y477710D03*
X355300Y502700D03*
X357700Y499000D03*
X400080Y500854D03*
X384849Y525499D03*
Y521681D03*
X355300Y506100D03*
Y513500D03*
X386367Y474700D03*
X400080Y519500D03*
Y491107D03*
Y523903D03*
Y528243D03*
X389349Y480100D03*
X381986Y515631D03*
X374751Y485636D03*
X374715Y498722D03*
X366950Y464700D03*
X341500Y520400D03*
X373699Y521160D03*
X359100Y503200D03*
X374800Y516912D03*
X387450Y467000D03*
X389288Y483500D03*
X358800Y478000D03*
X370900Y464700D03*
X349088Y500296D03*
X373500Y540305D03*
X393912Y568499D03*
X351600Y540600D03*
X348314Y585614D03*
X385600Y529107D03*
X372600Y576207D03*
X374292Y580300D03*
X355012Y582324D03*
X363008Y547309D03*
X371227Y566830D03*
X384950Y560496D03*
X383000Y577000D03*
X386305Y581647D03*
X362700Y551200D03*
X361279Y581647D03*
X362100Y574700D03*
X349000Y581360D03*
X379050Y539931D03*
X341740Y535800D03*
X352279Y580294D03*
X346303Y591947D03*
X386723Y544565D03*
X342440Y571770D03*
X361900Y570800D03*
X369500Y542900D03*
X388641Y549747D03*
X400093Y536351D03*
X399726Y562327D03*
X399946Y558677D03*
X345259Y557566D03*
X391993Y582154D03*
X362300Y555200D03*
X343840Y566440D03*
X348300Y565400D03*
X364900Y585171D03*
X372939Y559838D03*
X346590Y572090D03*
X350278Y572306D03*
X366270Y563400D03*
X373222Y535938D03*
X370247Y546218D03*
X370223Y549965D03*
X384950Y551876D03*
Y555276D03*
X383056Y563675D03*
X400060Y554743D03*
X393912Y571899D03*
X393910Y575305D03*
X341493Y541250D03*
X393912Y578705D03*
X348600Y643500D03*
X344564Y628104D03*
X379400Y641800D03*
X385163Y641354D03*
X342133Y603008D03*
X391150Y613429D03*
X350500Y647600D03*
X355000Y652160D03*
X374200Y645871D03*
X370200Y636400D03*
X359036Y635900D03*
X359258Y596820D03*
X383300Y600600D03*
X384410Y633530D03*
X348000Y612661D03*
X352720Y600970D03*
X367133Y596067D03*
X382380Y612277D03*
X352400Y626102D03*
X372408Y629626D03*
X364014Y593996D03*
X343797Y631417D03*
X381967Y616123D03*
X361227Y630300D03*
X377700Y595000D03*
X383199Y623168D03*
X382438Y608755D03*
X384158Y638105D03*
X380443D03*
X400064Y652598D03*
X384300Y619925D03*
X354102Y660666D03*
X392720Y697500D03*
X376342Y711260D03*
X358296Y672460D03*
X346465Y703185D03*
X364200Y713100D03*
X369600Y693400D03*
X351100Y712100D03*
X384220Y700618D03*
X367600Y696800D03*
X396166Y692630D03*
X343200Y667600D03*
X389999Y664697D03*
X367700Y685450D03*
X343338Y679236D03*
X399999Y673422D03*
X396419Y679708D03*
X398983Y706749D03*
X382308Y665022D03*
X396419Y686586D03*
X372350Y698400D03*
X399093Y703350D03*
X380300Y703000D03*
X399154Y699950D03*
X341900Y690350D03*
X346600Y714500D03*
X346000Y684300D03*
X383800Y688400D03*
X392800Y677600D03*
X341934Y662794D03*
X378595Y664960D03*
X388626Y715509D03*
X392500Y692500D03*
X355298Y711750D03*
X396419Y683186D03*
X459950Y58000D03*
X469058Y49156D03*
X439200Y22100D03*
X439549Y26339D03*
X439554Y30429D03*
X439302Y34040D03*
X458972Y49634D03*
X462625Y49881D03*
X467300Y20000D03*
X450454Y38147D03*
X448520Y49979D03*
X430800Y22200D03*
X433600Y19900D03*
X428001Y25269D03*
X433400Y63373D03*
X438600Y91033D03*
X419662Y71426D03*
X423340Y71621D03*
X469901Y94047D03*
X415211Y71263D03*
X461736Y111300D03*
X442800Y90934D03*
X496700Y32100D03*
X482693Y42200D03*
X478500Y19775D03*
X490050Y45900D03*
X506970Y18693D03*
X502830D03*
X477400Y69300D03*
X512806Y49494D03*
X473151Y50052D03*
X521200Y57600D03*
X496035Y46435D03*
X503814Y56676D03*
X515500Y57900D03*
X486568Y38006D03*
X486114Y41700D03*
X496430Y22890D03*
X491270Y18877D03*
X485674Y32924D03*
X524950Y16120D03*
X473172Y95508D03*
X479147Y102165D03*
X490100Y111300D03*
X486400Y74700D03*
X481800Y71200D03*
X513909Y85849D03*
X510408Y85779D03*
X559200Y36265D03*
X552540Y64530D03*
X599422Y51662D03*
X568430Y50010D03*
X596489Y14110D03*
X559600Y47600D03*
X575550Y42800D03*
X601311Y13521D03*
X569300Y66274D03*
X545200Y69000D03*
X596300Y66950D03*
X549550Y61900D03*
X597950Y58950D03*
X573600Y49750D03*
X577100Y78600D03*
X545300Y75600D03*
X568000Y70000D03*
X584550Y80750D03*
X559900Y88400D03*
X563268Y88872D03*
X540179Y111036D03*
X539346Y114333D03*
X578900Y82500D03*
X551500Y82400D03*
X599682Y103715D03*
X547100Y79900D03*
X578400Y74500D03*
X562160Y178600D03*
X582219Y386612D03*
X599998Y391270D03*
X598964Y354128D03*
X596077Y369579D03*
X602075Y339970D03*
X593064Y400910D03*
X593229Y397308D03*
X666535Y26149D03*
X665800Y7550D03*
X666400Y22200D03*
X638470Y164470D03*
X634910Y169360D03*
X644100Y199850D03*
X630000Y169600D03*
X629500Y187500D03*
X619980Y197550D03*
X634000Y187500D03*
X630800Y147600D03*
X634800Y147700D03*
X666700Y205600D03*
X629400Y217300D03*
X644100Y203350D03*
X634450Y252100D03*
X631550Y249850D03*
X625926Y247530D03*
X627200Y253550D03*
X625250Y264250D03*
X625550Y244150D03*
Y240750D03*
X645516Y225334D03*
X620750Y258050D03*
X642547Y226992D03*
X632958Y231000D03*
X633109Y234397D03*
X632900Y238000D03*
X628300Y230550D03*
X625700Y235750D03*
X640141Y259859D03*
X640400Y217600D03*
X636491Y217592D03*
X633092Y217496D03*
X659500Y205300D03*
X662900D03*
X645400Y264050D03*
X620160Y203500D03*
X648700Y292900D03*
X660700Y292200D03*
X634830Y292095D03*
X638453Y291949D03*
X633400Y274600D03*
X652850Y269600D03*
X642300Y276450D03*
X649000Y273500D03*
X652100Y279300D03*
X656700Y305607D03*
X664600Y306100D03*
X648700Y303600D03*
X652500Y305707D03*
X638603Y296320D03*
X642003Y296249D03*
X645403Y296229D03*
X631069Y292512D03*
X654670Y391494D03*
X616428Y379533D03*
X626772Y371336D03*
X612300Y344300D03*
X613480Y333710D03*
X629900Y339300D03*
X610300Y354800D03*
X654600Y367600D03*
X639318Y354003D03*
X643082Y353941D03*
X629239Y387969D03*
X620100Y384100D03*
X608600Y362600D03*
X659300Y373100D03*
X637000Y373856D03*
X632220Y389694D03*
X607800Y382362D03*
X607100Y351200D03*
X638360Y383805D03*
X642270Y383869D03*
X605400Y393400D03*
X618600Y364375D03*
X609240Y370337D03*
X616900Y343000D03*
X615150Y364200D03*
X640968Y370425D03*
X606626Y354723D03*
X637353Y379591D03*
X657900Y443200D03*
X655100Y436900D03*
X636963Y405999D03*
X632180Y397968D03*
X654300Y504100D03*
X613000Y463000D03*
X666216Y470684D03*
X632800Y561600D03*
X620160Y544793D03*
X610200Y555400D03*
X628160Y569095D03*
X619400Y570451D03*
X653600Y540300D03*
X635970Y557600D03*
X638660Y568043D03*
X616160Y542700D03*
X614000Y561250D03*
X606600Y551100D03*
X722150Y174300D03*
X727150Y184550D03*
X722150D03*
X711150Y174300D03*
X716650Y184550D03*
X711150D03*
X705650D03*
X677770Y196410D03*
X730550Y179050D03*
X732000Y185900D03*
X716650Y174400D03*
X674300Y198900D03*
X704579Y258164D03*
X721261Y240551D03*
X721260Y234252D03*
X730710Y256302D03*
X733858Y256299D03*
Y253149D03*
X730710Y253152D03*
X733859Y234253D03*
Y237403D03*
X730710D03*
Y234254D03*
X733858Y243700D03*
Y246849D03*
Y249999D03*
Y265747D03*
X730710Y240553D03*
Y243702D03*
Y246852D03*
Y250002D03*
Y265750D03*
X721295Y221651D03*
X718089Y243684D03*
X721260Y253150D03*
Y259449D03*
Y265748D03*
X721261Y246851D03*
X733859Y240552D03*
X727559Y259449D03*
Y265748D03*
Y253150D03*
Y240551D03*
X727560Y246851D03*
X727559Y221654D03*
Y234252D03*
X727594Y227950D03*
X696600Y241500D03*
X701500Y250564D03*
X691600Y207600D03*
X718121Y256326D03*
X718089Y246834D03*
X718098Y259423D03*
X718072Y265748D03*
X718089Y249984D03*
X718129Y253144D03*
X693800Y264300D03*
X725466Y200819D03*
X707923Y219765D03*
X708900Y214500D03*
X718111Y224802D03*
X706500Y212150D03*
X709615Y223228D03*
X718111Y231101D03*
X696300Y215750D03*
X702900Y212350D03*
X707679Y233664D03*
X718111Y227952D03*
X722322Y200935D03*
X704279Y226664D03*
X705529Y231064D03*
X705779Y236764D03*
X706079Y240664D03*
X710716Y235827D03*
X714945Y234230D03*
X726988Y204312D03*
X718123Y201101D03*
X710079Y203664D03*
X718895Y207125D03*
X705364Y205864D03*
X713168Y207689D03*
X718111Y221653D03*
X733859Y215355D03*
X718110Y234252D03*
X709679Y239164D03*
X727560Y215355D03*
X716116Y207469D03*
X718111Y237401D03*
X709079Y229564D03*
X703979Y219995D03*
X718111Y240550D03*
X711812Y243700D03*
X714961D03*
X730709Y215355D03*
X724410D03*
X732264Y204312D03*
X703320Y203900D03*
X733859Y212206D03*
X729800Y208400D03*
X730709Y221654D03*
X733858D03*
X724410D03*
Y234252D03*
Y240551D03*
Y246850D03*
Y253150D03*
Y227953D03*
Y265748D03*
Y259449D03*
X704579Y261964D03*
X682030Y253630D03*
X706100Y250000D03*
X690600Y230700D03*
X691243Y211743D03*
X692600Y201300D03*
X677800Y215900D03*
X724410Y281496D03*
X730710D03*
X733859D03*
Y275198D03*
X730710Y272048D03*
X733858Y268897D03*
X721820Y315750D03*
X730710Y268899D03*
X721260Y275196D03*
Y272047D03*
X733859Y278346D03*
X677300Y314900D03*
X681200D03*
X684400Y313400D03*
X688000Y313200D03*
X694675Y323900D03*
X730708Y290944D03*
X724409D03*
X727559Y272047D03*
Y278346D03*
X708100Y331410D03*
X718340Y315800D03*
X706796Y295829D03*
X726895Y309117D03*
X711799Y304234D03*
X713339Y306954D03*
X724063Y306305D03*
X698039Y285854D03*
X707834Y293060D03*
X707079Y286964D03*
X704079Y300964D03*
X719200Y307400D03*
X705579Y298464D03*
X695508Y288964D03*
X710679Y267894D03*
X721230Y284653D03*
X718099Y290964D03*
X710329Y285214D03*
X718117Y281465D03*
X718080Y284653D03*
X701708Y292364D03*
X706277Y279162D03*
X718072Y278346D03*
X708409Y276771D03*
X733892Y297246D03*
X730708Y297243D03*
X714619Y303884D03*
X692750Y293200D03*
X718109Y272034D03*
X694307Y283485D03*
X722468Y308964D03*
X727558Y297243D03*
X733859Y272048D03*
X690579Y299964D03*
X675555Y318736D03*
X672350Y317600D03*
X724409Y297243D03*
X700323Y283078D03*
X716300Y331340D03*
X733859Y284646D03*
X695300Y306700D03*
X718099Y287814D03*
X712410Y331320D03*
X702250Y329650D03*
X733857Y290944D03*
X727558D03*
X730300Y314900D03*
X724410Y272047D03*
Y278346D03*
Y284645D03*
X669950Y310950D03*
X681800Y287950D03*
X718137Y275186D03*
X702939Y281484D03*
X718109Y268934D03*
X714949Y287814D03*
X731400Y362700D03*
X727000Y353000D03*
X712417Y352800D03*
X718300Y362900D03*
X722500Y353000D03*
X718000D03*
X713500Y362900D03*
X729900Y393200D03*
X708300Y445800D03*
X709006Y410206D03*
X721504Y402321D03*
X699900Y453600D03*
X691813Y407210D03*
X691874Y410741D03*
X691873Y403800D03*
X690550Y453850D03*
X690300Y460200D03*
X720900Y412900D03*
X728874Y470860D03*
X725366Y470722D03*
X677275Y485625D03*
X683583Y485841D03*
X702824Y476476D03*
X682400Y463400D03*
X696800Y476400D03*
X689100Y507900D03*
X730600Y493100D03*
X716078Y492334D03*
X672500Y507100D03*
X696000Y508400D03*
X715391Y479109D03*
X703440Y548820D03*
X710459Y554134D03*
X719626Y590829D03*
X725000Y576100D03*
X714800Y567956D03*
X710000Y549100D03*
X710100Y545600D03*
X705176Y593429D03*
X717450Y551554D03*
X697200Y529200D03*
X705676Y562429D03*
X722300Y608200D03*
X708600Y608500D03*
X702515Y597064D03*
X693900Y597800D03*
X703800Y608400D03*
X712708Y603038D03*
X723369Y599835D03*
X722122Y611840D03*
X777550Y62350D03*
X795832Y66750D03*
X787360Y35650D03*
X776300Y47600D03*
X769812Y53660D03*
X756431Y54010D03*
X736803Y52087D03*
X779400Y54750D03*
X746500Y47200D03*
X780815Y47062D03*
X776600Y35250D03*
X762765Y42200D03*
X761900Y81700D03*
X772700Y113000D03*
X794650Y86050D03*
X769710Y125150D03*
X766110Y125270D03*
X793957Y113436D03*
X761950Y126450D03*
X773200Y97600D03*
X781250Y101750D03*
X779594Y126865D03*
X762000Y113000D03*
X763825Y89975D03*
X776500Y82700D03*
X750500Y118500D03*
X750600Y114200D03*
X769500Y91000D03*
X792600Y101300D03*
X772800Y107550D03*
X776850Y115050D03*
X749600Y199300D03*
X749400Y195600D03*
X753800Y181500D03*
X753400Y185400D03*
X741300Y185700D03*
X738160Y199480D03*
X749900Y185200D03*
X786343Y179959D03*
X745700Y185900D03*
X769100Y187800D03*
X786388Y183429D03*
X772810Y179901D03*
X772700Y183300D03*
X737000Y185900D03*
X765900Y191900D03*
X764900Y207200D03*
X768505Y243702D03*
X784277Y243713D03*
X784253Y227953D03*
Y231103D03*
X752756Y234253D03*
Y231103D03*
Y224804D03*
Y227954D03*
X749606Y231103D03*
Y234253D03*
Y227954D03*
Y224804D03*
X737008Y256299D03*
X740158D03*
Y253149D03*
X737008D03*
X771655Y237402D03*
X765353D03*
X737009Y237400D03*
X737008Y243700D03*
Y246849D03*
Y249999D03*
Y265747D03*
X740158Y246849D03*
Y265747D03*
X740122Y243700D03*
X740158Y249999D03*
X752756Y221654D03*
X737008D03*
X771654Y253150D03*
X777954Y237402D03*
Y227953D03*
Y231103D03*
X765355Y265749D03*
X771654Y259449D03*
Y265749D03*
X793701Y221654D03*
X781103Y227954D03*
X784277Y246863D03*
X784267Y259426D03*
X746457Y224804D03*
X755906D03*
X737009Y227953D03*
Y234253D03*
Y231103D03*
X774804Y221655D03*
Y224804D03*
Y227954D03*
X746457D03*
X755906D03*
X746457Y231103D03*
X755906D03*
X746457Y234253D03*
X755906D03*
X759056Y253150D03*
X765355Y234253D03*
X765354Y231102D03*
X765355Y227953D03*
X765354Y246850D03*
X784277Y253162D03*
X740132Y240562D03*
X759055Y221654D03*
X765355Y224804D03*
X771654Y215355D03*
Y209056D03*
Y212205D03*
X746457Y240552D03*
X752757D03*
X759056D03*
X746421Y253149D03*
X749455Y202200D03*
X765354Y221654D03*
X743307D03*
X762205Y215355D03*
X781103Y237402D03*
Y231103D03*
X787402Y221654D03*
X787401Y215354D03*
X746457Y246850D03*
X752720Y253149D03*
X752757Y246851D03*
X765355Y253150D03*
X759056Y246851D03*
X746433Y265761D03*
X746457Y259449D03*
X752757D03*
Y265749D03*
X765355Y259449D03*
X759056Y265749D03*
X759031Y259461D03*
X777976Y265761D03*
X784267Y256276D03*
X793701Y231103D03*
X793672Y243709D03*
X799991Y249972D03*
X799972Y262588D03*
X796822D03*
Y256289D03*
X790551Y259486D03*
X790538Y265723D03*
X793701Y237402D03*
X777976Y259461D03*
X781102Y221654D03*
X749606D03*
X762205Y212205D03*
X761600Y207300D03*
X787402Y240552D03*
Y243701D03*
X793700Y256262D03*
X752759Y218499D03*
X755909Y218514D03*
X790550Y253150D03*
X799972Y256309D03*
X781080Y265763D03*
X784258Y262618D03*
X777967Y262576D03*
X790523Y256289D03*
X800021Y243717D03*
X795593Y206063D03*
X777953Y256300D03*
X781300Y207800D03*
X774803Y265749D03*
X737009Y240552D03*
X746457Y215355D03*
X737029Y215337D03*
X743279Y215364D03*
X740158Y215355D03*
X743279Y212196D03*
X741294Y208274D03*
X743008Y206059D03*
X765355Y240552D03*
X743307Y246850D03*
X762217Y240526D03*
X755880Y240563D03*
X749580D03*
X755869Y253149D03*
X762167Y246850D03*
X755907Y246851D03*
X749569Y246850D03*
X762168Y253149D03*
X749608Y253150D03*
X743282Y253161D03*
X755868Y265748D03*
X755882Y259461D03*
X762218Y259425D03*
X749582Y259461D03*
X743282D03*
X762181Y265762D03*
X749582Y265761D03*
X743282D03*
X743281Y240562D03*
X768480Y265762D03*
X768518Y259425D03*
X768467Y253149D03*
Y246850D03*
X771653Y246887D03*
X762205Y221654D03*
X784252D03*
X777953D03*
X790551D03*
X740158D03*
X755906D03*
X746457D03*
X793701Y234254D03*
X781127Y246863D03*
X793672Y240560D03*
X796821Y246859D03*
X793701Y227954D03*
X796850Y221654D03*
X793674Y265758D03*
X793699Y262634D03*
X768504Y215355D03*
X763963Y331837D03*
X766437Y329363D03*
X769266Y326534D03*
X748737Y330263D03*
X751566Y327434D03*
X762229Y290933D03*
X752756Y278346D03*
X759073Y287810D03*
X774826Y268910D03*
X737009Y281496D03*
X740159Y278345D03*
Y281496D03*
X759031Y275209D03*
X765356Y272048D03*
Y275197D03*
Y278347D03*
X740158Y275197D03*
Y272046D03*
X737008D03*
Y268897D03*
X740158D03*
X746457Y272047D03*
Y275197D03*
X752757D03*
X752731Y272060D03*
X762181D03*
X759031D03*
X762206Y275197D03*
Y278347D03*
X737009Y275196D03*
X790551Y284646D03*
X781100Y287800D03*
X787419Y278354D03*
X737007Y290944D03*
X749579Y297254D03*
X787402Y297243D03*
X781102Y297244D03*
X771654Y297243D03*
X759058Y300414D03*
X768503Y287794D03*
X774802D03*
X787400Y287795D03*
X749607Y275197D03*
X774789Y275174D03*
X784221Y284652D03*
X777915Y281496D03*
X762189Y281514D03*
X768489Y281474D03*
X777953Y275198D03*
Y278347D03*
X784290Y272047D03*
X743306Y290944D03*
X749606Y278346D03*
X749593Y284670D03*
X799999Y290944D03*
Y284645D03*
Y278345D03*
X799974Y272058D03*
X793701Y300393D03*
X790519Y272053D03*
X790550Y287795D03*
X749605Y290944D03*
X762204Y287794D03*
X781064Y272047D03*
X784243Y278318D03*
X780300Y309300D03*
X740157Y297243D03*
X737008Y297244D03*
X740158Y284646D03*
X744881Y309000D03*
X743306Y297243D03*
X790526Y300406D03*
X765369Y281474D03*
X771669D03*
X781120Y284665D03*
X759070Y281514D03*
X749816Y303716D03*
X777790Y304778D03*
X769768Y304464D03*
X759208Y304284D03*
X784252Y268885D03*
X796839Y290934D03*
X787438Y275197D03*
X796832Y272064D03*
X796875Y304331D03*
X796862Y281522D03*
X784249Y281464D03*
X787426Y272060D03*
X790551Y278384D03*
X743308Y284646D03*
X746457D03*
X737009D03*
X744400Y322800D03*
X746456Y297243D03*
X765353Y287794D03*
X771653D03*
X777952D03*
X784251D03*
X762225Y297227D03*
X755898Y287804D03*
X743283Y272060D03*
X755882D03*
X749581D03*
X746456Y290944D03*
X740157D03*
X793700Y297243D03*
X796849D03*
X790545Y290959D03*
X793694D03*
X793703Y287797D03*
X796839Y287784D03*
X793675Y284637D03*
X793679Y281508D03*
X793675Y278357D03*
X796868Y278364D03*
X793737Y275196D03*
X793682Y272064D03*
X793683Y268879D03*
X796850Y268910D03*
X799534Y339466D03*
X760252Y353266D03*
X763081Y350437D03*
X765555Y347963D03*
X768384Y345134D03*
X761134Y334666D03*
X772352Y341266D03*
X775181Y338437D03*
X777655Y335963D03*
X780484Y333134D03*
X777434Y353566D03*
X780263Y350737D03*
X782737Y348263D03*
X785566Y345434D03*
X789334Y341766D03*
X792163Y338937D03*
X794637Y336463D03*
X797466Y333634D03*
X743434Y335566D03*
X746263Y332737D03*
X749534Y346566D03*
X752363Y343737D03*
X754837Y341263D03*
X757666Y338434D03*
X795026Y374556D03*
X799426Y374456D03*
X738465Y352935D03*
X790357Y377781D03*
X774700Y483600D03*
X794700Y505200D03*
X747125Y483924D03*
X743726Y483813D03*
X755500Y492600D03*
X768500Y480000D03*
X740253Y483893D03*
X797323Y512162D03*
X782000Y505600D03*
X771184Y514916D03*
X745700Y498250D03*
X742300Y498200D03*
X759000Y482900D03*
X759169Y497414D03*
X750600Y497400D03*
X759200Y508000D03*
X777600Y512200D03*
X781700Y510900D03*
X736600Y500000D03*
X780750Y496750D03*
X781050Y492550D03*
X757099Y530082D03*
X763809Y537191D03*
X782709Y537691D03*
X753099Y530282D03*
X795922Y531500D03*
X747200Y611900D03*
X826925Y57425D03*
X802786Y57150D03*
X841300Y54200D03*
X818785Y50692D03*
X803000Y117100D03*
X813349Y73142D03*
X809349Y73197D03*
X821962Y189277D03*
X801385Y183067D03*
X801340Y179597D03*
X831504Y199129D03*
X843419Y261781D03*
X840591Y264609D03*
X837619Y255281D03*
X834791Y258109D03*
X831609Y261291D03*
X828781Y264119D03*
X836955Y245662D03*
X834127Y248490D03*
X830945Y251672D03*
X828117Y254500D03*
X832148Y204444D03*
X816079Y250464D03*
X802227Y208424D03*
X802246Y205826D03*
X807468Y234464D03*
X808923Y245979D03*
X806968Y253464D03*
X804600Y210800D03*
X808400D03*
X816900Y231700D03*
X803160Y259454D03*
X803150Y256336D03*
X807177Y261023D03*
X814262Y218950D03*
X810277Y243190D03*
X810688Y238944D03*
X803129Y240535D03*
X803158Y237414D03*
X806862Y243302D03*
X806918Y237804D03*
X826000Y233400D03*
X828000Y243100D03*
X854419Y307581D03*
X851591Y310409D03*
X848409Y313591D03*
X845581Y316419D03*
X858919Y292081D03*
X856091Y294909D03*
X852909Y298091D03*
X850081Y300919D03*
X852919Y286081D03*
X850091Y288909D03*
X846909Y292091D03*
X844081Y294919D03*
X849419Y267581D03*
X846591Y270409D03*
X843409Y273591D03*
X840581Y276419D03*
X847419Y280581D03*
X844591Y283409D03*
X841409Y286591D03*
X838581Y289419D03*
X837409Y267791D03*
X834581Y270619D03*
X807666Y331334D03*
X822817Y331022D03*
X825646Y328193D03*
X803300Y303700D03*
X810300Y326450D03*
X823250Y319350D03*
X814450Y306950D03*
X810079Y271264D03*
X809968Y290464D03*
X808400Y300900D03*
X812164Y279674D03*
X811600Y317300D03*
X802363Y336637D03*
X804837Y334163D03*
X817514Y336325D03*
X820343Y333496D03*
X810946Y389734D03*
X811112Y393735D03*
X857581Y391433D03*
X817700Y385700D03*
X851100Y407500D03*
X861000Y410500D03*
X806400Y398700D03*
X810100Y404934D03*
X857000Y410600D03*
X850950Y489300D03*
X846000Y476100D03*
X849050Y481050D03*
X809384Y484984D03*
X800800Y526900D03*
X804584Y526584D03*
X829500Y481500D03*
X821050Y533350D03*
X813150Y533450D03*
X888551Y226649D03*
X882871Y243771D03*
X892449Y241249D03*
X886300Y221150D03*
X896969Y301500D03*
X883240Y301973D03*
X888668Y322100D03*
X886540Y388996D03*
X872750Y403400D03*
X1129450Y786650D03*
G54D23*
X339331Y49803D03*
X360669Y91929D03*
X1129450Y140350D03*
G54D32*
X629921Y57874D03*
X708661D03*
X1129450Y505650D03*
G54D14*
X70865Y98425D03*
Y472440D03*
X314960D03*
X405511Y39370D03*
X364173Y740157D03*
X612204Y433070D03*
Y740157D03*
X875984Y433070D03*
Y740157D03*
X1129450Y477550D03*
G54D15*
X89764Y238386D03*
X309252Y413583D03*
X1129450Y112250D03*
G54D24*
X339331Y91929D03*
X360669Y49803D03*
X1129450Y168450D03*
G54D33*
X638780Y69685D03*
X629921D03*
X621063D03*
X641732Y117323D03*
X638780Y114567D03*
X635827Y120079D03*
X632873Y117323D03*
X629921Y114567D03*
X626969Y120079D03*
X624015Y117323D03*
X621063Y114567D03*
X618110Y120079D03*
X641732Y102362D03*
X638780Y99606D03*
X635827Y105118D03*
X632873Y102362D03*
X629921Y99606D03*
X621063D03*
X624015Y102362D03*
X626969Y105118D03*
X618110D03*
X641732Y87402D03*
X638780Y84646D03*
X635827Y90157D03*
X632873Y87402D03*
X626969Y90157D03*
X629921Y84646D03*
X624015Y87402D03*
X621063Y84646D03*
X618110Y90157D03*
X641732Y72441D03*
X635827Y75197D03*
X632873Y72441D03*
X626969Y75197D03*
X624015Y72441D03*
X618110Y75197D03*
X717520Y69685D03*
X708661D03*
X699803D03*
X720472Y117323D03*
X717520Y114567D03*
X714567Y120079D03*
X711613Y117323D03*
X708661Y114567D03*
X705709Y120079D03*
X702755Y117323D03*
X699803Y114567D03*
X696850Y120079D03*
X720472Y102362D03*
X717520Y99606D03*
X714567Y105118D03*
X711613Y102362D03*
X708661Y99606D03*
X699803D03*
X702755Y102362D03*
X705709Y105118D03*
X696850D03*
X720472Y87402D03*
X717520Y84646D03*
X714567Y90157D03*
X711613Y87402D03*
X705709Y90157D03*
X708661Y84646D03*
X702755Y87402D03*
X699803Y84646D03*
X696850Y90157D03*
X720472Y72441D03*
X714567Y75197D03*
X711613Y72441D03*
X705709Y75197D03*
X702755Y72441D03*
X696850Y75197D03*
X1129450Y674250D03*
G54D34*
X651575Y20039D03*
X608267D03*
X641732Y126811D03*
X624015D03*
X651575Y72441D03*
X608267D03*
X730315Y20039D03*
X687007D03*
X720472Y126811D03*
X702755D03*
X730315Y72441D03*
X687007D03*
X1129450Y618050D03*
G54D25*
X305906Y182874D03*
X1129450Y337050D03*
G54D16*
X49213Y740157D03*
X875985Y59055D03*
X1129450Y449450D03*
G54D17*
X65900Y671000D03*
X65700Y660900D03*
X70600Y665800D03*
X60700Y665900D03*
X70800Y660700D03*
X60800Y660900D03*
X70700Y671000D03*
X60600Y670900D03*
X65714Y665850D03*
X135019Y706095D03*
X130019D03*
X139916Y705822D03*
X130019Y724095D03*
X135019Y714845D03*
Y719095D03*
Y723595D03*
Y710595D03*
X130019Y720495D03*
Y716895D03*
Y713295D03*
Y709695D03*
X139916Y723822D03*
Y720222D03*
Y716622D03*
Y713022D03*
Y709422D03*
X306486Y643750D03*
X306286Y633650D03*
X311186Y638550D03*
X301286Y638650D03*
X311386Y633450D03*
X301386Y633650D03*
X311286Y643750D03*
X301186Y643650D03*
X306300Y638600D03*
X295634Y710070D03*
X290520Y715120D03*
X300620Y715220D03*
X290720Y705120D03*
X300720Y704920D03*
X290620Y710120D03*
X300520Y710020D03*
X295620Y705120D03*
X295820Y715220D03*
X371400Y606400D03*
X358900Y612800D03*
X358800Y606300D03*
X365300Y606500D03*
X371400Y612700D03*
X371300Y618800D03*
X365500Y619000D03*
X358900Y618800D03*
X365164Y612620D03*
X468000Y35400D03*
X464000Y35500D03*
X468000Y39500D03*
Y31500D03*
X472000Y35500D03*
X601500Y363600D03*
X629200Y536040D03*
X629080Y539920D03*
X625500Y536100D03*
X625300Y539900D03*
X700546Y577599D03*
X691796D03*
X691296Y572599D03*
X705696D03*
X696296Y577599D03*
X709296Y572599D03*
Y577599D03*
X702096Y572599D03*
X694896D03*
X698496D03*
X704796Y577599D03*
X709569Y582496D03*
X698769D03*
X695169D03*
X691569D03*
X702369D03*
X705969D03*
X810200Y494900D03*
X815100Y499800D03*
X805200Y499900D03*
X815300Y494700D03*
X805300Y494900D03*
X815200Y505000D03*
X805100Y504900D03*
X810214Y499850D03*
X810400Y505000D03*
X1129450Y730450D03*
G54D35*
X652756Y180000D03*
X865353Y332598D03*
X1129450Y224650D03*
G54D26*
X305906Y388386D03*
X1129450Y365150D03*
G54D36*
G01X-13131Y-65072D02*
Y-145072D01*
G01D02*
X1244069D01*
G01X-29131Y-65072D02*
Y-33072D01*
G01X-13131Y-65072D02*
X1244069D01*
G01X-13131Y-100572D02*
X1244069D01*
G01X-17131Y-49072D02*
G02I-12000J0D01*
G01X-22281D02*
G02I-6850J0D01*
G01X-13131D02*
X-45131D01*
G01X456569Y-65072D02*
Y-145072D01*
G01X594069Y-65072D02*
Y-145072D01*
G01X709069Y-65072D02*
Y-145072D01*
G01X876569Y-65072D02*
Y-145072D01*
G01X1046569Y-65072D02*
Y-145072D01*
G01X1244069Y-65072D02*
Y-145072D01*
G01X1272069Y-49072D02*
G02I-12000J0D01*
G01X1266919D02*
G02I-6850J0D01*
G01X1276069D02*
X1244069D01*
G01X1260069Y-65072D02*
Y-33072D01*
G54D27*
X346457Y66850D03*
Y57007D03*
X353543Y70787D03*
Y62913D03*
Y55039D03*
X346457Y74724D03*
Y84567D03*
X353543Y86535D03*
Y78661D03*
X1129450Y589950D03*
G54D18*
X90157Y413583D03*
X309055Y157677D03*
X1129450Y196550D03*
G54D37*
G01X13215Y-125739D02*
X14089Y-124864D01*
X14744Y-123406D01*
X15181Y-121363D01*
X14744Y-119614D01*
X13871Y-118447D01*
X12342Y-117572D01*
X6447D01*
Y-135072D01*
X13652D01*
X15181Y-133906D01*
X16054Y-132155D01*
X16491Y-130114D01*
X16054Y-128072D01*
X14744Y-126322D01*
X13215Y-125739D01*
X6447D01*
G01X25912Y-135072D02*
Y-123406D01*
G01Y-125739D02*
X27004Y-124572D01*
X28096Y-123697D01*
X29624Y-123406D01*
X30715Y-123697D01*
X32026Y-124572D01*
G01X41884Y-140322D02*
X43194Y-140905D01*
X44941Y-140322D01*
X46032Y-139156D01*
X46906Y-137697D01*
X48215Y-133031D01*
X51054Y-123406D01*
G01X44067D02*
X48215Y-133031D01*
G01X67462Y-124864D02*
X65934Y-123697D01*
X64624Y-123406D01*
X62877Y-123989D01*
X61567Y-125155D01*
X60694Y-127197D01*
X60475Y-129239D01*
X60694Y-131281D01*
X61567Y-133031D01*
X62877Y-134489D01*
X64624Y-135072D01*
X66152Y-134489D01*
X67462Y-133322D01*
G01X78194Y-127197D02*
X85181D01*
X84526Y-125155D01*
X83434Y-123989D01*
X81906Y-123406D01*
X80377Y-123697D01*
X79067Y-124572D01*
X78194Y-126614D01*
X77757Y-128364D01*
Y-130114D01*
X78194Y-131864D01*
X79286Y-133614D01*
X80596Y-134780D01*
X82124Y-135072D01*
X83652Y-134489D01*
X85181Y-132739D01*
G01X121272Y-119031D02*
X119962Y-118155D01*
X118434Y-117572D01*
X116687D01*
X114722Y-118447D01*
X113194Y-119905D01*
X112102Y-121656D01*
X111229Y-124572D01*
X111010Y-127197D01*
X111447Y-129822D01*
X112102Y-131572D01*
X113412Y-133322D01*
X114941Y-134489D01*
X116469Y-135072D01*
X117997D01*
X119526Y-134489D01*
X120836Y-133614D01*
X121928Y-132448D01*
G01X137899Y-135072D02*
Y-123406D01*
G01Y-125447D02*
X137026Y-124281D01*
X135715Y-123697D01*
X134187Y-123406D01*
X132659Y-123989D01*
X131349Y-125155D01*
X130475Y-126905D01*
X130039Y-129239D01*
X130475Y-131572D01*
X131349Y-133322D01*
X132659Y-134489D01*
X134187Y-135072D01*
X135715Y-134780D01*
X137026Y-133906D01*
X137899Y-132739D01*
G01X147757Y-135072D02*
Y-123406D01*
G01Y-126322D02*
X148631Y-124864D01*
X149941Y-123697D01*
X151687Y-123406D01*
X153215Y-123697D01*
X154526Y-124864D01*
X155181Y-126905D01*
Y-135072D01*
G01X164384Y-140322D02*
X165694Y-140905D01*
X167441Y-140322D01*
X168532Y-139156D01*
X169406Y-137697D01*
X170715Y-133031D01*
X173554Y-123406D01*
G01X166567D02*
X170715Y-133031D01*
G01X186469Y-135072D02*
X185159Y-134780D01*
X183849Y-133614D01*
X182975Y-131572D01*
X182539Y-129239D01*
X182975Y-126905D01*
X183849Y-124864D01*
X185159Y-123697D01*
X186469Y-123406D01*
X187779Y-123697D01*
X189089Y-124864D01*
X189962Y-126905D01*
X190181Y-129239D01*
X189962Y-131572D01*
X189089Y-133614D01*
X187779Y-134780D01*
X186469Y-135072D01*
G01X200257D02*
Y-123406D01*
G01Y-126322D02*
X201131Y-124864D01*
X202441Y-123697D01*
X204187Y-123406D01*
X205715Y-123697D01*
X207026Y-124864D01*
X207681Y-126905D01*
Y-135072D01*
G01X236349Y-117572D02*
X241589D01*
G01X238969D02*
Y-135072D01*
G01X236349D02*
X241589D01*
G01X256469D02*
X254722Y-134780D01*
X253194Y-133614D01*
X251884Y-131864D01*
X251010Y-129822D01*
X250574Y-127489D01*
Y-125155D01*
X251010Y-122822D01*
X251884Y-120780D01*
X253194Y-119031D01*
X254722Y-117864D01*
X256469Y-117572D01*
X258215Y-117864D01*
X259744Y-119031D01*
X261054Y-120780D01*
X261928Y-122822D01*
X262364Y-125155D01*
Y-127489D01*
X261928Y-129822D01*
X261054Y-131864D01*
X259744Y-133614D01*
X258215Y-134780D01*
X256469Y-135072D01*
G01X268292D02*
Y-117572D01*
X273969Y-132155D01*
X279646Y-117572D01*
Y-135072D01*
G01X307877Y-140905D02*
X305694Y-137989D01*
X304602Y-135072D01*
Y-123406D01*
X305694Y-120489D01*
X307877Y-117572D01*
G01X321010Y-123406D02*
X323631Y-135072D01*
X326469Y-123406D01*
X329307Y-135072D01*
X331928Y-123406D01*
G01X340039Y-135655D02*
X347899Y-117572D01*
G01X376349D02*
X381589D01*
G01X378969D02*
Y-135072D01*
G01X376349D02*
X381589D01*
G01X396469D02*
X394722Y-134780D01*
X393194Y-133614D01*
X391884Y-131864D01*
X391010Y-129822D01*
X390574Y-127489D01*
Y-125155D01*
X391010Y-122822D01*
X391884Y-120780D01*
X393194Y-119031D01*
X394722Y-117864D01*
X396469Y-117572D01*
X398215Y-117864D01*
X399744Y-119031D01*
X401054Y-120780D01*
X401928Y-122822D01*
X402364Y-125155D01*
Y-127489D01*
X401928Y-129822D01*
X401054Y-131864D01*
X399744Y-133614D01*
X398215Y-134780D01*
X396469Y-135072D01*
G01X418772Y-119031D02*
X417462Y-118155D01*
X415934Y-117572D01*
X414187D01*
X412222Y-118447D01*
X410694Y-119905D01*
X409602Y-121656D01*
X408729Y-124572D01*
X408510Y-127197D01*
X408947Y-129822D01*
X409602Y-131572D01*
X410912Y-133322D01*
X412441Y-134489D01*
X413969Y-135072D01*
X415497D01*
X417026Y-134489D01*
X418336Y-133614D01*
X419428Y-132448D01*
G01X432561Y-140905D02*
X434744Y-137989D01*
X435836Y-135072D01*
Y-123406D01*
X434744Y-120489D01*
X432561Y-117572D01*
G01X96464Y231686D02*
X83064D01*
G02Y245086I0J6700D01*
G01X96464D01*
G02Y231686I0J-6700D01*
G01X89631Y245086D02*
X89614Y251086D01*
G01X88117Y250082D02*
X89631Y245086D01*
X91117Y250090D01*
X88117Y250082D01*
G01X180792Y-90072D02*
Y-72572D01*
X186469Y-87155D01*
X192146Y-72572D01*
Y-90072D01*
G01X203969D02*
X202659Y-89780D01*
X201349Y-88614D01*
X200475Y-86572D01*
X200039Y-84239D01*
X200475Y-81905D01*
X201349Y-79864D01*
X202659Y-78697D01*
X203969Y-78406D01*
X205279Y-78697D01*
X206589Y-79864D01*
X207462Y-81905D01*
X207681Y-84239D01*
X207462Y-86572D01*
X206589Y-88614D01*
X205279Y-89780D01*
X203969Y-90072D01*
G01X225399Y-72572D02*
Y-90072D01*
G01Y-87448D02*
X224526Y-88906D01*
X223215Y-89780D01*
X221687Y-90072D01*
X219941Y-89489D01*
X218631Y-88031D01*
X217757Y-86281D01*
X217539Y-84239D01*
X217757Y-82197D01*
X218631Y-80447D01*
X219941Y-78989D01*
X221687Y-78406D01*
X223215Y-78697D01*
X224307Y-79281D01*
X225399Y-80447D01*
G01X235694Y-82197D02*
X242681D01*
X242026Y-80155D01*
X240934Y-78989D01*
X239406Y-78406D01*
X237877Y-78697D01*
X236567Y-79572D01*
X235694Y-81614D01*
X235257Y-83364D01*
Y-85114D01*
X235694Y-86864D01*
X236786Y-88614D01*
X238096Y-89780D01*
X239624Y-90072D01*
X241152Y-89489D01*
X242681Y-87739D01*
G01X256469Y-90072D02*
Y-72572D01*
G01X339087Y53961D02*
X331693Y66135D01*
G01X335209Y57456D02*
X339087Y53961D01*
X337773Y59013D01*
X335209Y57456D01*
G01X337731Y47253D02*
Y52353D01*
G02X340931I1600J0D01*
G01Y47253D01*
G02X337731I-1600J0D01*
G01X338990Y89207D02*
X332106Y76109D01*
G01X337992Y84083D02*
X338990Y89207D01*
X335336Y85479D01*
X337992Y84083D01*
G01X337731Y90729D02*
Y93129D01*
G02X340931I1600J0D01*
G01Y90729D01*
G02X337731I-1600J0D01*
G01X309119Y420283D02*
X309102Y426283D01*
G01X307605Y425279D02*
X309119Y420283D01*
X310605Y425287D01*
X307605Y425279D01*
G01X315952Y406883D02*
X302552D01*
G02Y420283I0J6700D01*
G01X315952D01*
G02Y406883I0J-6700D01*
G01X360758Y52599D02*
X366749Y65506D01*
G01X361503Y57766D02*
X360758Y52599D01*
X364224Y56503D01*
X361503Y57766D01*
G01X359069Y48603D02*
Y51003D01*
G02X362269I1600J0D01*
G01Y48603D01*
G02X359069I-1600J0D01*
G01X361363Y87973D02*
X366239Y76500D01*
G01X364699Y83958D02*
X361363Y87973D01*
X361938Y82785D01*
X364699Y83958D01*
G01X359069Y89379D02*
Y94479D01*
G02X362269I1600J0D01*
G01Y89379D01*
G02X359069I-1600J0D01*
G01X490269Y-135072D02*
Y-117572D01*
X487649Y-121072D01*
G01Y-135072D02*
X492889D01*
G01X503621Y-127781D02*
X505149Y-125739D01*
X506459Y-124572D01*
X508206Y-123989D01*
X509734Y-124572D01*
X510826Y-125739D01*
X511699Y-127489D01*
X511917Y-129530D01*
X511699Y-131281D01*
X510826Y-133031D01*
X509515Y-134489D01*
X507987Y-135072D01*
X506241Y-134489D01*
X504712Y-132739D01*
X503839Y-130114D01*
X503621Y-127197D01*
X504057Y-123406D01*
X504712Y-121363D01*
X505804Y-119322D01*
X507332Y-117864D01*
X508861Y-117572D01*
X510389Y-118155D01*
X511481Y-119614D01*
G01X520466Y-131572D02*
X521775Y-133614D01*
X523522Y-134780D01*
X525487Y-135072D01*
X527234Y-134780D01*
X528981Y-133322D01*
X530072Y-131572D01*
X530291Y-129822D01*
X529854Y-127781D01*
X528326Y-126322D01*
X526797Y-125739D01*
X524832D01*
G01X526797D02*
X528107Y-124864D01*
X529199Y-123406D01*
X529636Y-121656D01*
X529199Y-119905D01*
X528107Y-118447D01*
X526142Y-117572D01*
X524177Y-117864D01*
X522212Y-119031D01*
G01X542769Y-135072D02*
Y-117572D01*
X540149Y-121072D01*
G01Y-135072D02*
X545389D01*
G01X560269D02*
X561797Y-134780D01*
X563544Y-133906D01*
X564636Y-132448D01*
X565072Y-130405D01*
X564636Y-128364D01*
X563326Y-126614D01*
X561361Y-125739D01*
X559177D01*
X557867Y-125155D01*
X556775Y-123697D01*
X556339Y-121656D01*
X556994Y-119614D01*
X558522Y-118155D01*
X560269Y-117572D01*
X562015Y-118155D01*
X563544Y-119614D01*
X564199Y-121656D01*
X563762Y-123697D01*
X562671Y-125155D01*
X561361Y-125739D01*
X559177D01*
X557212Y-126614D01*
X555902Y-128364D01*
X555466Y-130405D01*
X555902Y-132448D01*
X556994Y-133906D01*
X558741Y-134780D01*
X560269Y-135072D01*
G01X477152Y-90072D02*
Y-72572D01*
X482392D01*
X484139Y-73447D01*
X485449Y-75489D01*
X485886Y-77822D01*
X485449Y-80155D01*
X484357Y-81905D01*
X482392Y-82781D01*
X477152D01*
G01X503822Y-74031D02*
X502512Y-73155D01*
X500984Y-72572D01*
X499237D01*
X497272Y-73447D01*
X495744Y-74905D01*
X494652Y-76656D01*
X493779Y-79572D01*
X493560Y-82197D01*
X493997Y-84822D01*
X494652Y-86572D01*
X495962Y-88322D01*
X497491Y-89489D01*
X499019Y-90072D01*
X500547D01*
X502076Y-89489D01*
X503386Y-88614D01*
X504478Y-87448D01*
G01X518265Y-80739D02*
X519139Y-79864D01*
X519794Y-78406D01*
X520231Y-76363D01*
X519794Y-74614D01*
X518921Y-73447D01*
X517392Y-72572D01*
X511497D01*
Y-90072D01*
X518702D01*
X520231Y-88906D01*
X521104Y-87155D01*
X521541Y-85114D01*
X521104Y-83072D01*
X519794Y-81322D01*
X518265Y-80739D01*
X511497D01*
G01X527469Y-95905D02*
X540569D01*
G01X546497Y-90072D02*
Y-72572D01*
X556541Y-90072D01*
Y-72572D01*
G01X569019Y-90072D02*
X567272Y-89780D01*
X565744Y-88614D01*
X564434Y-86864D01*
X563560Y-84822D01*
X563124Y-82489D01*
Y-80155D01*
X563560Y-77822D01*
X564434Y-75780D01*
X565744Y-74031D01*
X567272Y-72864D01*
X569019Y-72572D01*
X570765Y-72864D01*
X572294Y-74031D01*
X573604Y-75780D01*
X574478Y-77822D01*
X574914Y-80155D01*
Y-82489D01*
X574478Y-84822D01*
X573604Y-86864D01*
X572294Y-88614D01*
X570765Y-89780D01*
X569019Y-90072D01*
G01X647421Y-120489D02*
X648731Y-118739D01*
X650259Y-117864D01*
X652006Y-117572D01*
X654189Y-118155D01*
X655717Y-119614D01*
X656154Y-121363D01*
X655936Y-123114D01*
X655062Y-124572D01*
X650696Y-127489D01*
X648731Y-129530D01*
X647421Y-132448D01*
X646984Y-135072D01*
X656154D01*
G01X619860Y-72572D02*
X625319Y-90072D01*
X630778Y-72572D01*
G01X647186Y-90072D02*
X638452D01*
Y-72572D01*
X647186D01*
G01X643692Y-81030D02*
X638452D01*
G01X655952Y-90072D02*
Y-72572D01*
X661411D01*
X663157Y-73447D01*
X664249Y-74614D01*
X664686Y-76947D01*
X664249Y-79281D01*
X662939Y-80739D01*
X661411Y-81614D01*
X655952D01*
G01X661411D02*
X664686Y-90072D01*
G01X677819Y-90655D02*
X677382Y-90364D01*
Y-89780D01*
X677819Y-89489D01*
X678256Y-89780D01*
Y-90364D01*
X677819Y-90655D01*
G01X752966Y-135072D02*
Y-117572D01*
X757332D01*
X759079Y-118447D01*
X760389Y-119614D01*
X761481Y-121363D01*
X762354Y-123406D01*
X762572Y-126322D01*
X762354Y-129239D01*
X761481Y-131281D01*
X760389Y-133031D01*
X759079Y-134197D01*
X757332Y-135072D01*
X752966D01*
G01X770902D02*
Y-117572D01*
X776361D01*
X778107Y-118447D01*
X779199Y-119614D01*
X779636Y-121947D01*
X779199Y-124281D01*
X777889Y-125739D01*
X776361Y-126614D01*
X770902D01*
G01X776361D02*
X779636Y-135072D01*
G01X790149Y-117572D02*
X795389D01*
G01X792769D02*
Y-135072D01*
G01X790149D02*
X795389D01*
G01X805902Y-117572D02*
Y-135072D01*
X814636D01*
G01X823402Y-117572D02*
Y-135072D01*
X832136D01*
G01X753402Y-72572D02*
Y-90072D01*
X762136D01*
G01X779199D02*
Y-78406D01*
G01Y-80447D02*
X778326Y-79281D01*
X777015Y-78697D01*
X775487Y-78406D01*
X773959Y-78989D01*
X772649Y-80155D01*
X771775Y-81905D01*
X771339Y-84239D01*
X771775Y-86572D01*
X772649Y-88322D01*
X773959Y-89489D01*
X775487Y-90072D01*
X777015Y-89780D01*
X778326Y-88906D01*
X779199Y-87739D01*
G01X788184Y-95322D02*
X789494Y-95905D01*
X791241Y-95322D01*
X792332Y-94156D01*
X793206Y-92697D01*
X794515Y-88031D01*
X797354Y-78406D01*
G01X790367D02*
X794515Y-88031D01*
G01X806994Y-82197D02*
X813981D01*
X813326Y-80155D01*
X812234Y-78989D01*
X810706Y-78406D01*
X809177Y-78697D01*
X807867Y-79572D01*
X806994Y-81614D01*
X806557Y-83364D01*
Y-85114D01*
X806994Y-86864D01*
X808086Y-88614D01*
X809396Y-89780D01*
X810924Y-90072D01*
X812452Y-89489D01*
X813981Y-87739D01*
G01X824712Y-90072D02*
Y-78406D01*
G01Y-80739D02*
X825804Y-79572D01*
X826896Y-78697D01*
X828424Y-78406D01*
X829515Y-78697D01*
X830826Y-79572D01*
G01X917819Y-135072D02*
X916072Y-134780D01*
X914544Y-133614D01*
X913234Y-131864D01*
X912360Y-129822D01*
X911924Y-127489D01*
Y-125155D01*
X912360Y-122822D01*
X913234Y-120780D01*
X914544Y-119031D01*
X916072Y-117864D01*
X917819Y-117572D01*
X919565Y-117864D01*
X921094Y-119031D01*
X922404Y-120780D01*
X923278Y-122822D01*
X923714Y-125155D01*
Y-127489D01*
X923278Y-129822D01*
X922404Y-131864D01*
X921094Y-133614D01*
X919565Y-134780D01*
X917819Y-135072D01*
G01X919565Y-130405D02*
X922186Y-135072D01*
G01X930516Y-117572D02*
Y-130114D01*
X931389Y-132739D01*
X933136Y-134489D01*
X935319Y-135072D01*
X937502Y-134489D01*
X939249Y-132739D01*
X940122Y-130114D01*
Y-117572D01*
G01X950199D02*
X955439D01*
G01X952819D02*
Y-135072D01*
G01X950199D02*
X955439D01*
G01X965297D02*
Y-117572D01*
X975341Y-135072D01*
Y-117572D01*
G01X992622Y-119031D02*
X991312Y-118155D01*
X989784Y-117572D01*
X988037D01*
X986072Y-118447D01*
X984544Y-119905D01*
X983452Y-121656D01*
X982579Y-124572D01*
X982360Y-127197D01*
X982797Y-129822D01*
X983452Y-131572D01*
X984762Y-133322D01*
X986291Y-134489D01*
X987819Y-135072D01*
X989347D01*
X990876Y-134489D01*
X992186Y-133614D01*
X993278Y-132448D01*
G01X1005319Y-135072D02*
Y-127197D01*
X1000952Y-117572D01*
G01X1009686D02*
X1005319Y-127197D01*
G01X895516Y-90072D02*
Y-72572D01*
X899882D01*
X901629Y-73447D01*
X902939Y-74614D01*
X904031Y-76363D01*
X904904Y-78406D01*
X905122Y-81322D01*
X904904Y-84239D01*
X904031Y-86281D01*
X902939Y-88031D01*
X901629Y-89197D01*
X899882Y-90072D01*
X895516D01*
G01X914544Y-82197D02*
X921531D01*
X920876Y-80155D01*
X919784Y-78989D01*
X918256Y-78406D01*
X916727Y-78697D01*
X915417Y-79572D01*
X914544Y-81614D01*
X914107Y-83364D01*
Y-85114D01*
X914544Y-86864D01*
X915636Y-88614D01*
X916946Y-89780D01*
X918474Y-90072D01*
X920002Y-89489D01*
X921531Y-87739D01*
G01X932044Y-88031D02*
X933136Y-89197D01*
X934664Y-90072D01*
X935974D01*
X937284Y-89489D01*
X938157Y-88614D01*
X938594Y-87448D01*
X938376Y-85697D01*
X937502Y-84822D01*
X933572Y-83072D01*
X932699Y-81030D01*
X933136Y-79572D01*
X934009Y-78697D01*
X935319Y-78406D01*
X936629Y-78697D01*
X937939Y-79572D01*
G01X952819Y-78406D02*
Y-90072D01*
G01Y-73739D02*
X952382Y-73447D01*
Y-72864D01*
X952819Y-72572D01*
X953256Y-72864D01*
Y-73447D01*
X952819Y-73739D01*
G01X967262Y-94447D02*
X968791Y-95614D01*
X970537Y-95905D01*
X972065Y-95614D01*
X973376Y-94156D01*
X974249Y-92114D01*
Y-78406D01*
G01Y-80739D02*
X973376Y-79572D01*
X972065Y-78697D01*
X970537Y-78406D01*
X968791Y-78989D01*
X967699Y-80155D01*
X966825Y-82197D01*
X966389Y-84239D01*
X966607Y-85989D01*
X967481Y-88031D01*
X968791Y-89489D01*
X970537Y-90072D01*
X971847Y-89780D01*
X973376Y-88614D01*
X974249Y-87448D01*
G01X984107Y-90072D02*
Y-78406D01*
G01Y-81322D02*
X984981Y-79864D01*
X986291Y-78697D01*
X988037Y-78406D01*
X989565Y-78697D01*
X990876Y-79864D01*
X991531Y-81905D01*
Y-90072D01*
G01X1002044Y-82197D02*
X1009031D01*
X1008376Y-80155D01*
X1007284Y-78989D01*
X1005756Y-78406D01*
X1004227Y-78697D01*
X1002917Y-79572D01*
X1002044Y-81614D01*
X1001607Y-83364D01*
Y-85114D01*
X1002044Y-86864D01*
X1003136Y-88614D01*
X1004446Y-89780D01*
X1005974Y-90072D01*
X1007502Y-89489D01*
X1009031Y-87739D01*
G01X1019762Y-90072D02*
Y-78406D01*
G01Y-80739D02*
X1020854Y-79572D01*
X1021946Y-78697D01*
X1023474Y-78406D01*
X1024565Y-78697D01*
X1025876Y-79572D01*
G01X1066519Y-117572D02*
X1064772Y-118155D01*
X1063462Y-119614D01*
X1062589Y-121363D01*
X1061934Y-123697D01*
X1061716Y-126322D01*
X1061934Y-128947D01*
X1062589Y-131281D01*
X1063462Y-133031D01*
X1064772Y-134489D01*
X1066519Y-135072D01*
X1068265Y-134489D01*
X1069576Y-133031D01*
X1070449Y-131281D01*
X1071104Y-128947D01*
X1071322Y-126322D01*
X1071104Y-123697D01*
X1070449Y-121363D01*
X1069576Y-119614D01*
X1068265Y-118155D01*
X1066519Y-117572D01*
G01X1084019Y-135072D02*
X1085547Y-134780D01*
X1087294Y-133906D01*
X1088386Y-132448D01*
X1088822Y-130405D01*
X1088386Y-128364D01*
X1087076Y-126614D01*
X1085111Y-125739D01*
X1082927D01*
X1081617Y-125155D01*
X1080525Y-123697D01*
X1080089Y-121656D01*
X1080744Y-119614D01*
X1082272Y-118155D01*
X1084019Y-117572D01*
X1085765Y-118155D01*
X1087294Y-119614D01*
X1087949Y-121656D01*
X1087512Y-123697D01*
X1086421Y-125155D01*
X1085111Y-125739D01*
X1082927D01*
X1080962Y-126614D01*
X1079652Y-128364D01*
X1079216Y-130405D01*
X1079652Y-132448D01*
X1080744Y-133906D01*
X1082491Y-134780D01*
X1084019Y-135072D01*
G01X1097589Y-135655D02*
X1105449Y-117572D01*
G01X1119019D02*
X1117272Y-118155D01*
X1115962Y-119614D01*
X1115089Y-121363D01*
X1114434Y-123697D01*
X1114216Y-126322D01*
X1114434Y-128947D01*
X1115089Y-131281D01*
X1115962Y-133031D01*
X1117272Y-134489D01*
X1119019Y-135072D01*
X1120765Y-134489D01*
X1122076Y-133031D01*
X1122949Y-131281D01*
X1123604Y-128947D01*
X1123822Y-126322D01*
X1123604Y-123697D01*
X1122949Y-121363D01*
X1122076Y-119614D01*
X1120765Y-118155D01*
X1119019Y-117572D01*
G01X1136082Y-135072D02*
X1136519Y-131281D01*
X1137174Y-128072D01*
X1138047Y-125155D01*
X1139139Y-121947D01*
X1140886Y-117572D01*
X1132152D01*
G01X1150089Y-135655D02*
X1157949Y-117572D01*
G01X1167371Y-120489D02*
X1168681Y-118739D01*
X1170209Y-117864D01*
X1171956Y-117572D01*
X1174139Y-118155D01*
X1175667Y-119614D01*
X1176104Y-121363D01*
X1175886Y-123114D01*
X1175012Y-124572D01*
X1170646Y-127489D01*
X1168681Y-129530D01*
X1167371Y-132448D01*
X1166934Y-135072D01*
X1176104D01*
G01X1189019Y-117572D02*
X1187272Y-118155D01*
X1185962Y-119614D01*
X1185089Y-121363D01*
X1184434Y-123697D01*
X1184216Y-126322D01*
X1184434Y-128947D01*
X1185089Y-131281D01*
X1185962Y-133031D01*
X1187272Y-134489D01*
X1189019Y-135072D01*
X1190765Y-134489D01*
X1192076Y-133031D01*
X1192949Y-131281D01*
X1193604Y-128947D01*
X1193822Y-126322D01*
X1193604Y-123697D01*
X1192949Y-121363D01*
X1192076Y-119614D01*
X1190765Y-118155D01*
X1189019Y-117572D01*
G01X1206519Y-135072D02*
Y-117572D01*
X1203899Y-121072D01*
G01Y-135072D02*
X1209139D01*
G01X1223582D02*
X1224019Y-131281D01*
X1224674Y-128072D01*
X1225547Y-125155D01*
X1226639Y-121947D01*
X1228386Y-117572D01*
X1219652D01*
G01X1114216Y-90072D02*
Y-72572D01*
X1118582D01*
X1120329Y-73447D01*
X1121639Y-74614D01*
X1122731Y-76363D01*
X1123604Y-78406D01*
X1123822Y-81322D01*
X1123604Y-84239D01*
X1122731Y-86281D01*
X1121639Y-88031D01*
X1120329Y-89197D01*
X1118582Y-90072D01*
X1114216D01*
G01X1140449D02*
Y-78406D01*
G01Y-80447D02*
X1139576Y-79281D01*
X1138265Y-78697D01*
X1136737Y-78406D01*
X1135209Y-78989D01*
X1133899Y-80155D01*
X1133025Y-81905D01*
X1132589Y-84239D01*
X1133025Y-86572D01*
X1133899Y-88322D01*
X1135209Y-89489D01*
X1136737Y-90072D01*
X1138265Y-89780D01*
X1139576Y-88906D01*
X1140449Y-87739D01*
G01X1154019Y-72572D02*
Y-90072D01*
G01X1150962Y-78406D02*
X1157076D01*
G01X1168244Y-82197D02*
X1175231D01*
X1174576Y-80155D01*
X1173484Y-78989D01*
X1171956Y-78406D01*
X1170427Y-78697D01*
X1169117Y-79572D01*
X1168244Y-81614D01*
X1167807Y-83364D01*
Y-85114D01*
X1168244Y-86864D01*
X1169336Y-88614D01*
X1170646Y-89780D01*
X1172174Y-90072D01*
X1173702Y-89489D01*
X1175231Y-87739D01*
G01X1085585Y68200D02*
Y80700D01*
X1092715Y68200D01*
Y80700D01*
G01X1101550Y68200D02*
X1100620Y68408D01*
X1099690Y69241D01*
X1099070Y70700D01*
X1098760Y72367D01*
X1099070Y74033D01*
X1099690Y75492D01*
X1100620Y76325D01*
X1101550Y76533D01*
X1102480Y76325D01*
X1103410Y75492D01*
X1104030Y74033D01*
X1104185Y72367D01*
X1104030Y70700D01*
X1103410Y69241D01*
X1102480Y68408D01*
X1101550Y68200D01*
G01X1113950Y80700D02*
Y68200D01*
G01X1111780Y76533D02*
X1116120D01*
G01X1124025Y73825D02*
X1128985D01*
X1128520Y75283D01*
X1127745Y76117D01*
X1126660Y76533D01*
X1125575Y76325D01*
X1124645Y75700D01*
X1124025Y74242D01*
X1123715Y72991D01*
Y71742D01*
X1124025Y70492D01*
X1124800Y69241D01*
X1125730Y68408D01*
X1126815Y68200D01*
X1127900Y68617D01*
X1128985Y69866D01*
G01X1138750Y67783D02*
X1138440Y67992D01*
Y68408D01*
X1138750Y68617D01*
X1139060Y68408D01*
Y67992D01*
X1138750Y67783D01*
G01Y73408D02*
X1138440Y73617D01*
Y74033D01*
X1138750Y74242D01*
X1139060Y74033D01*
Y73617D01*
X1138750Y73408D01*
G01X1148050Y68200D02*
Y80700D01*
X1151925D01*
X1153165Y80075D01*
X1153940Y79242D01*
X1154250Y77575D01*
X1153940Y75908D01*
X1153010Y74867D01*
X1151925Y74242D01*
X1148050D01*
G01X1151925D02*
X1154250Y68200D01*
G01X1161225Y73825D02*
X1166185D01*
X1165720Y75283D01*
X1164945Y76117D01*
X1163860Y76533D01*
X1162775Y76325D01*
X1161845Y75700D01*
X1161225Y74242D01*
X1160915Y72991D01*
Y71742D01*
X1161225Y70492D01*
X1162000Y69241D01*
X1162930Y68408D01*
X1164015Y68200D01*
X1165100Y68617D01*
X1166185Y69866D01*
G01X1175020Y68200D02*
Y78825D01*
X1175330Y79866D01*
X1175950Y80492D01*
X1176880Y80700D01*
X1177810Y80283D01*
X1178275Y79242D01*
G01X1176415Y75700D02*
X1173315D01*
G01X1186025Y73825D02*
X1190985D01*
X1190520Y75283D01*
X1189745Y76117D01*
X1188660Y76533D01*
X1187575Y76325D01*
X1186645Y75700D01*
X1186025Y74242D01*
X1185715Y72991D01*
Y71742D01*
X1186025Y70492D01*
X1186800Y69241D01*
X1187730Y68408D01*
X1188815Y68200D01*
X1189900Y68617D01*
X1190985Y69866D01*
G01X1198580Y68200D02*
Y76533D01*
G01Y74867D02*
X1199355Y75700D01*
X1200130Y76325D01*
X1201215Y76533D01*
X1201990Y76325D01*
X1202920Y75700D01*
G01X1225550Y80700D02*
Y68200D01*
G01X1223380Y76533D02*
X1227720D01*
G01X1237950Y68200D02*
X1237020Y68408D01*
X1236090Y69241D01*
X1235470Y70700D01*
X1235160Y72367D01*
X1235470Y74033D01*
X1236090Y75492D01*
X1237020Y76325D01*
X1237950Y76533D01*
X1238880Y76325D01*
X1239810Y75492D01*
X1240430Y74033D01*
X1240585Y72367D01*
X1240430Y70700D01*
X1239810Y69241D01*
X1238880Y68408D01*
X1237950Y68200D01*
G01X1259340D02*
Y80700D01*
X1262440D01*
X1263680Y80075D01*
X1264610Y79242D01*
X1265385Y77992D01*
X1266005Y76533D01*
X1266160Y74450D01*
X1266005Y72367D01*
X1265385Y70908D01*
X1264610Y69658D01*
X1263680Y68825D01*
X1262440Y68200D01*
X1259340D01*
G01X1272050D02*
Y80700D01*
X1275925D01*
X1277165Y80075D01*
X1277940Y79242D01*
X1278250Y77575D01*
X1277940Y75908D01*
X1277010Y74867D01*
X1275925Y74242D01*
X1272050D01*
G01X1275925D02*
X1278250Y68200D01*
G01X1285690Y80700D02*
X1289410D01*
G01X1287550D02*
Y68200D01*
G01X1285690D02*
X1289410D01*
G01X1296850Y80700D02*
Y68200D01*
X1303050D01*
G01X1309250Y80700D02*
Y68200D01*
X1315450D01*
G01X1337150D02*
Y80700D01*
G01X1352340Y68200D02*
Y76533D01*
G01Y75075D02*
X1351720Y75908D01*
X1350790Y76325D01*
X1349705Y76533D01*
X1348620Y76117D01*
X1347690Y75283D01*
X1347070Y74033D01*
X1346760Y72367D01*
X1347070Y70700D01*
X1347690Y69450D01*
X1348620Y68617D01*
X1349705Y68200D01*
X1350790Y68408D01*
X1351720Y69033D01*
X1352340Y69866D01*
G01X1358695Y64450D02*
X1359625Y64033D01*
X1360865Y64450D01*
X1361640Y65283D01*
X1362260Y66325D01*
X1363190Y69658D01*
X1365205Y76533D01*
G01X1360245D02*
X1363190Y69658D01*
G01X1372025Y73825D02*
X1376985D01*
X1376520Y75283D01*
X1375745Y76117D01*
X1374660Y76533D01*
X1373575Y76325D01*
X1372645Y75700D01*
X1372025Y74242D01*
X1371715Y72991D01*
Y71742D01*
X1372025Y70492D01*
X1372800Y69241D01*
X1373730Y68408D01*
X1374815Y68200D01*
X1375900Y68617D01*
X1376985Y69866D01*
G01X1384580Y68200D02*
Y76533D01*
G01Y74867D02*
X1385355Y75700D01*
X1386130Y76325D01*
X1387215Y76533D01*
X1387990Y76325D01*
X1388920Y75700D01*
G01X1410620Y68200D02*
Y78825D01*
X1410930Y79866D01*
X1411550Y80492D01*
X1412480Y80700D01*
X1413410Y80283D01*
X1413875Y79242D01*
G01X1412015Y75700D02*
X1408915D01*
G01X1423950Y68200D02*
X1423020Y68408D01*
X1422090Y69241D01*
X1421470Y70700D01*
X1421160Y72367D01*
X1421470Y74033D01*
X1422090Y75492D01*
X1423020Y76325D01*
X1423950Y76533D01*
X1424880Y76325D01*
X1425810Y75492D01*
X1426430Y74033D01*
X1426585Y72367D01*
X1426430Y70700D01*
X1425810Y69241D01*
X1424880Y68408D01*
X1423950Y68200D01*
G01X1434180D02*
Y76533D01*
G01Y74867D02*
X1434955Y75700D01*
X1435730Y76325D01*
X1436815Y76533D01*
X1437590Y76325D01*
X1438520Y75700D01*
G01X1464250Y68200D02*
X1458050D01*
Y80700D01*
X1464250D01*
G01X1461770Y74658D02*
X1458050D01*
G01X1470450Y80700D02*
Y68200D01*
X1476650D01*
G01X1482850Y80700D02*
Y68200D01*
X1489050D01*
G01X1496490Y80700D02*
X1500210D01*
G01X1498350D02*
Y68200D01*
G01X1496490D02*
X1500210D01*
G01X1507650D02*
Y80700D01*
X1511370D01*
X1512610Y80075D01*
X1513540Y78617D01*
X1513850Y76950D01*
X1513540Y75283D01*
X1512765Y74033D01*
X1511370Y73408D01*
X1507650D01*
G01X1519895Y69866D02*
X1521135Y68825D01*
X1522530Y68200D01*
X1523770D01*
X1525010Y68825D01*
X1525940Y69866D01*
X1526405Y71325D01*
X1526095Y72783D01*
X1525320Y74033D01*
X1523925Y74867D01*
X1522065Y75283D01*
X1520980Y76117D01*
X1520515Y77575D01*
X1520825Y79033D01*
X1521600Y80075D01*
X1522685Y80700D01*
X1523770D01*
X1524855Y80283D01*
X1525785Y79242D01*
G01X1538650Y68200D02*
X1532450D01*
Y80700D01*
X1538650D01*
G01X1536170Y74658D02*
X1532450D01*
G01X1563140Y80700D02*
Y68200D01*
G01Y70075D02*
X1562520Y69033D01*
X1561590Y68408D01*
X1560505Y68200D01*
X1559265Y68617D01*
X1558335Y69658D01*
X1557715Y70908D01*
X1557560Y72367D01*
X1557715Y73825D01*
X1558335Y75075D01*
X1559265Y76117D01*
X1560505Y76533D01*
X1561590Y76325D01*
X1562365Y75908D01*
X1563140Y75075D01*
G01X1570580Y68200D02*
Y76533D01*
G01Y74867D02*
X1571355Y75700D01*
X1572130Y76325D01*
X1573215Y76533D01*
X1573990Y76325D01*
X1574920Y75700D01*
G01X1585150Y76533D02*
Y68200D01*
G01Y79866D02*
X1584840Y80075D01*
Y80492D01*
X1585150Y80700D01*
X1585460Y80492D01*
Y80075D01*
X1585150Y79866D01*
G01X1597550Y68200D02*
Y80700D01*
G01X1609950Y68200D02*
Y80700D01*
G01X1637540D02*
Y68200D01*
G01Y70075D02*
X1636920Y69033D01*
X1635990Y68408D01*
X1634905Y68200D01*
X1633665Y68617D01*
X1632735Y69658D01*
X1632115Y70908D01*
X1631960Y72367D01*
X1632115Y73825D01*
X1632735Y75075D01*
X1633665Y76117D01*
X1634905Y76533D01*
X1635990Y76325D01*
X1636765Y75908D01*
X1637540Y75075D01*
G01X1647150Y76533D02*
Y68200D01*
G01Y79866D02*
X1646840Y80075D01*
Y80492D01*
X1647150Y80700D01*
X1647460Y80492D01*
Y80075D01*
X1647150Y79866D01*
G01X1657380Y68200D02*
Y76533D01*
G01Y74867D02*
X1658155Y75700D01*
X1658930Y76325D01*
X1660015Y76533D01*
X1660790Y76325D01*
X1661720Y75700D01*
G01X1669625Y73825D02*
X1674585D01*
X1674120Y75283D01*
X1673345Y76117D01*
X1672260Y76533D01*
X1671175Y76325D01*
X1670245Y75700D01*
X1669625Y74242D01*
X1669315Y72991D01*
Y71742D01*
X1669625Y70492D01*
X1670400Y69241D01*
X1671330Y68408D01*
X1672415Y68200D01*
X1673500Y68617D01*
X1674585Y69866D01*
G01X1686830Y75492D02*
X1685745Y76325D01*
X1684815Y76533D01*
X1683575Y76117D01*
X1682645Y75283D01*
X1682025Y73825D01*
X1681870Y72367D01*
X1682025Y70908D01*
X1682645Y69658D01*
X1683575Y68617D01*
X1684815Y68200D01*
X1685900Y68617D01*
X1686830Y69450D01*
G01X1696750Y80700D02*
Y68200D01*
G01X1694580Y76533D02*
X1698920D01*
G01X1709150D02*
Y68200D01*
G01Y79866D02*
X1708840Y80075D01*
Y80492D01*
X1709150Y80700D01*
X1709460Y80492D01*
Y80075D01*
X1709150Y79866D01*
G01X1721550Y68200D02*
X1720620Y68408D01*
X1719690Y69241D01*
X1719070Y70700D01*
X1718760Y72367D01*
X1719070Y74033D01*
X1719690Y75492D01*
X1720620Y76325D01*
X1721550Y76533D01*
X1722480Y76325D01*
X1723410Y75492D01*
X1724030Y74033D01*
X1724185Y72367D01*
X1724030Y70700D01*
X1723410Y69241D01*
X1722480Y68408D01*
X1721550Y68200D01*
G01X1731315D02*
Y76533D01*
G01Y74450D02*
X1731935Y75492D01*
X1732865Y76325D01*
X1734105Y76533D01*
X1735190Y76325D01*
X1736120Y75492D01*
X1736585Y74033D01*
Y68200D01*
G01X1084500Y98200D02*
Y910000D01*
X1568100D01*
Y98200D01*
X1084500D01*
G01Y126300D02*
X1568100D01*
G01X1084500Y182500D02*
X1568100D01*
G01X1084500Y154400D02*
X1568100D01*
G01X1084500Y238700D02*
X1568100D01*
G01X1084500Y210600D02*
X1568100D01*
G01X1084500Y323000D02*
X1568100D01*
G01X1084500Y294900D02*
X1568100D01*
G01X1084500Y266800D02*
X1568100D01*
G01X1084500Y379200D02*
X1568100D01*
G01X1084500Y351100D02*
X1568100D01*
G01X1084500Y435400D02*
X1568100D01*
G01X1084500Y407300D02*
X1568100D01*
G01X1084500Y519700D02*
X1568100D01*
G01X1084500Y491600D02*
X1568100D01*
G01X1084500Y463500D02*
X1568100D01*
G01X1084500Y575900D02*
X1568100D01*
G01X1084500Y547800D02*
X1568100D01*
G01X1084500Y632100D02*
X1568100D01*
G01X1084500Y604000D02*
X1568100D01*
G01X1084500Y716400D02*
X1568100D01*
G01X1084500Y688300D02*
X1568100D01*
G01X1084500Y660200D02*
X1568100D01*
G01X1084500Y772600D02*
X1568100D01*
G01X1084500Y744500D02*
X1568100D01*
G01X1095505Y838150D02*
Y850650D01*
X1101395D01*
G01X1099225Y844608D02*
X1095505D01*
G01X1108990Y850650D02*
X1112710D01*
G01X1110850D02*
Y838150D01*
G01X1108990D02*
X1112710D01*
G01X1124180Y844400D02*
X1127280D01*
Y840650D01*
X1126350Y839400D01*
X1125265Y838567D01*
X1123715Y838150D01*
X1122165Y838567D01*
X1121080Y839400D01*
X1120150Y840650D01*
X1119530Y842108D01*
X1119220Y843775D01*
Y845233D01*
X1119530Y846483D01*
X1120150Y847942D01*
X1121080Y849192D01*
X1122010Y850025D01*
X1123250Y850650D01*
X1124335D01*
X1125575Y850233D01*
X1126505Y849400D01*
G01X1132240Y850650D02*
Y841692D01*
X1132860Y839816D01*
X1134100Y838567D01*
X1135650Y838150D01*
X1137200Y838567D01*
X1138440Y839816D01*
X1139060Y841692D01*
Y850650D01*
G01X1144950Y838150D02*
Y850650D01*
X1148825D01*
X1150065Y850025D01*
X1150840Y849192D01*
X1151150Y847525D01*
X1150840Y845858D01*
X1149910Y844817D01*
X1148825Y844192D01*
X1144950D01*
G01X1148825D02*
X1151150Y838150D01*
G01X1163550D02*
X1157350D01*
Y850650D01*
X1163550D01*
G01X1161070Y844608D02*
X1157350D01*
G01X1084500Y828800D02*
X1568100D01*
G01X1084500Y800700D02*
X1568100D01*
G01X1084500Y885000D02*
X1568100D01*
G01X1084500Y856900D02*
X1568100D01*
G01X1174400D02*
Y98200D01*
G01X1167890Y891250D02*
Y903750D01*
X1170990D01*
X1172230Y903125D01*
X1173160Y902292D01*
X1173935Y901042D01*
X1174555Y899583D01*
X1174710Y897500D01*
X1174555Y895417D01*
X1173935Y893958D01*
X1173160Y892708D01*
X1172230Y891875D01*
X1170990Y891250D01*
X1167890D01*
G01X1180600D02*
Y903750D01*
X1184475D01*
X1185715Y903125D01*
X1186490Y902292D01*
X1186800Y900625D01*
X1186490Y898958D01*
X1185560Y897917D01*
X1184475Y897292D01*
X1180600D01*
G01X1184475D02*
X1186800Y891250D01*
G01X1194240Y903750D02*
X1197960D01*
G01X1196100D02*
Y891250D01*
G01X1194240D02*
X1197960D01*
G01X1205400Y903750D02*
Y891250D01*
X1211600D01*
G01X1217800Y903750D02*
Y891250D01*
X1224000D01*
G01X1249110Y902708D02*
X1248180Y903333D01*
X1247095Y903750D01*
X1245855D01*
X1244460Y903125D01*
X1243375Y902083D01*
X1242600Y900833D01*
X1241980Y898750D01*
X1241825Y896875D01*
X1242135Y895000D01*
X1242600Y893750D01*
X1243530Y892500D01*
X1244615Y891667D01*
X1245700Y891250D01*
X1246785D01*
X1247870Y891667D01*
X1248800Y892291D01*
X1249575Y893125D01*
G01X1254845Y891250D02*
Y903750D01*
G01X1261355D02*
Y891250D01*
G01Y897500D02*
X1254845D01*
G01X1266625Y891250D02*
X1270500Y903750D01*
X1274375Y891250D01*
G01X1272980Y895625D02*
X1268020D01*
G01X1279800Y891250D02*
Y903750D01*
X1283675D01*
X1284915Y903125D01*
X1285690Y902292D01*
X1286000Y900625D01*
X1285690Y898958D01*
X1284760Y897917D01*
X1283675Y897292D01*
X1279800D01*
G01X1283675D02*
X1286000Y891250D01*
G01X1295300Y903750D02*
Y891250D01*
G01X1291735Y903750D02*
X1298865D01*
G01X1307700Y890833D02*
X1307390Y891042D01*
Y891458D01*
X1307700Y891667D01*
X1308010Y891458D01*
Y891042D01*
X1307700Y890833D01*
G01Y896458D02*
X1307390Y896667D01*
Y897083D01*
X1307700Y897292D01*
X1308010Y897083D01*
Y896667D01*
X1307700Y896458D01*
G01X1332500Y903750D02*
Y891250D01*
G01X1328935Y903750D02*
X1336065D01*
G01X1344900Y891250D02*
X1343660Y891458D01*
X1342575Y892291D01*
X1341645Y893542D01*
X1341025Y895000D01*
X1340715Y896667D01*
Y898333D01*
X1341025Y900000D01*
X1341645Y901458D01*
X1342575Y902708D01*
X1343660Y903542D01*
X1344900Y903750D01*
X1346140Y903542D01*
X1347225Y902708D01*
X1348155Y901458D01*
X1348775Y900000D01*
X1349085Y898333D01*
Y896667D01*
X1348775Y895000D01*
X1348155Y893542D01*
X1347225Y892291D01*
X1346140Y891458D01*
X1344900Y891250D01*
G01X1354200D02*
Y903750D01*
X1357920D01*
X1359160Y903125D01*
X1360090Y901667D01*
X1360400Y900000D01*
X1360090Y898333D01*
X1359315Y897083D01*
X1357920Y896458D01*
X1354200D01*
G01X1382100Y903750D02*
Y891250D01*
G01X1379930Y899583D02*
X1384270D01*
G01X1394500Y891250D02*
X1393570Y891458D01*
X1392640Y892291D01*
X1392020Y893750D01*
X1391710Y895417D01*
X1392020Y897083D01*
X1392640Y898542D01*
X1393570Y899375D01*
X1394500Y899583D01*
X1395430Y899375D01*
X1396360Y898542D01*
X1396980Y897083D01*
X1397135Y895417D01*
X1396980Y893750D01*
X1396360Y892291D01*
X1395430Y891458D01*
X1394500Y891250D01*
G01X1420540Y897917D02*
X1421160Y898542D01*
X1421625Y899583D01*
X1421935Y901042D01*
X1421625Y902292D01*
X1421005Y903125D01*
X1419920Y903750D01*
X1415735D01*
Y891250D01*
X1420850D01*
X1421935Y892083D01*
X1422555Y893333D01*
X1422865Y894792D01*
X1422555Y896250D01*
X1421625Y897500D01*
X1420540Y897917D01*
X1415735D01*
G01X1431700Y891250D02*
X1430460Y891458D01*
X1429375Y892291D01*
X1428445Y893542D01*
X1427825Y895000D01*
X1427515Y896667D01*
Y898333D01*
X1427825Y900000D01*
X1428445Y901458D01*
X1429375Y902708D01*
X1430460Y903542D01*
X1431700Y903750D01*
X1432940Y903542D01*
X1434025Y902708D01*
X1434955Y901458D01*
X1435575Y900000D01*
X1435885Y898333D01*
Y896667D01*
X1435575Y895000D01*
X1434955Y893542D01*
X1434025Y892291D01*
X1432940Y891458D01*
X1431700Y891250D01*
G01X1444100Y903750D02*
Y891250D01*
G01X1440535Y903750D02*
X1447665D01*
G01X1456500D02*
Y891250D01*
G01X1452935Y903750D02*
X1460065D01*
G01X1468900Y891250D02*
X1467660Y891458D01*
X1466575Y892291D01*
X1465645Y893542D01*
X1465025Y895000D01*
X1464715Y896667D01*
Y898333D01*
X1465025Y900000D01*
X1465645Y901458D01*
X1466575Y902708D01*
X1467660Y903542D01*
X1468900Y903750D01*
X1470140Y903542D01*
X1471225Y902708D01*
X1472155Y901458D01*
X1472775Y900000D01*
X1473085Y898333D01*
Y896667D01*
X1472775Y895000D01*
X1472155Y893542D01*
X1471225Y892291D01*
X1470140Y891458D01*
X1468900Y891250D01*
G01X1477270D02*
Y903750D01*
X1481300Y893333D01*
X1485330Y903750D01*
Y891250D01*
G01X1219350Y134100D02*
X1220435Y134308D01*
X1221675Y134933D01*
X1222450Y135975D01*
X1222760Y137433D01*
X1222450Y138891D01*
X1221520Y140142D01*
X1220125Y140767D01*
X1218575D01*
X1217645Y141183D01*
X1216870Y142225D01*
X1216560Y143683D01*
X1217025Y145142D01*
X1218110Y146183D01*
X1219350Y146600D01*
X1220590Y146183D01*
X1221675Y145142D01*
X1222140Y143683D01*
X1221830Y142225D01*
X1221055Y141183D01*
X1220125Y140767D01*
X1218575D01*
X1217180Y140142D01*
X1216250Y138891D01*
X1215940Y137433D01*
X1216250Y135975D01*
X1217025Y134933D01*
X1218265Y134308D01*
X1219350Y134100D01*
G01X1228340Y136600D02*
X1229270Y135141D01*
X1230510Y134308D01*
X1231905Y134100D01*
X1233145Y134308D01*
X1234385Y135350D01*
X1235160Y136600D01*
X1235315Y137850D01*
X1235005Y139308D01*
X1233920Y140350D01*
X1232835Y140767D01*
X1231440D01*
G01X1232835D02*
X1233765Y141392D01*
X1234540Y142433D01*
X1234850Y143683D01*
X1234540Y144933D01*
X1233765Y145975D01*
X1232370Y146600D01*
X1230975Y146392D01*
X1229580Y145558D01*
G01X1244150Y133683D02*
X1243840Y133892D01*
Y134308D01*
X1244150Y134517D01*
X1244460Y134308D01*
Y133892D01*
X1244150Y133683D01*
G01X1256550Y146600D02*
X1255310Y146183D01*
X1254380Y145142D01*
X1253760Y143892D01*
X1253295Y142225D01*
X1253140Y140350D01*
X1253295Y138475D01*
X1253760Y136808D01*
X1254380Y135558D01*
X1255310Y134517D01*
X1256550Y134100D01*
X1257790Y134517D01*
X1258720Y135558D01*
X1259340Y136808D01*
X1259805Y138475D01*
X1259960Y140350D01*
X1259805Y142225D01*
X1259340Y143892D01*
X1258720Y145142D01*
X1257790Y146183D01*
X1256550Y146600D01*
G01X1266625Y142433D02*
X1271275Y134100D01*
G01Y142433D02*
X1266625Y134100D01*
G01X1277940Y136600D02*
X1278870Y135141D01*
X1280110Y134308D01*
X1281505Y134100D01*
X1282745Y134308D01*
X1283985Y135350D01*
X1284760Y136600D01*
X1284915Y137850D01*
X1284605Y139308D01*
X1283520Y140350D01*
X1282435Y140767D01*
X1281040D01*
G01X1282435D02*
X1283365Y141392D01*
X1284140Y142433D01*
X1284450Y143683D01*
X1284140Y144933D01*
X1283365Y145975D01*
X1281970Y146600D01*
X1280575Y146392D01*
X1279180Y145558D01*
G01X1290805Y144517D02*
X1291735Y145766D01*
X1292820Y146392D01*
X1294060Y146600D01*
X1295610Y146183D01*
X1296695Y145142D01*
X1297005Y143892D01*
X1296850Y142641D01*
X1296230Y141600D01*
X1293130Y139517D01*
X1291735Y138058D01*
X1290805Y135975D01*
X1290495Y134100D01*
X1297005D01*
G01X1306150Y133683D02*
X1305840Y133892D01*
Y134308D01*
X1306150Y134517D01*
X1306460Y134308D01*
Y133892D01*
X1306150Y133683D01*
G01X1318550Y146600D02*
X1317310Y146183D01*
X1316380Y145142D01*
X1315760Y143892D01*
X1315295Y142225D01*
X1315140Y140350D01*
X1315295Y138475D01*
X1315760Y136808D01*
X1316380Y135558D01*
X1317310Y134517D01*
X1318550Y134100D01*
X1319790Y134517D01*
X1320720Y135558D01*
X1321340Y136808D01*
X1321805Y138475D01*
X1321960Y140350D01*
X1321805Y142225D01*
X1321340Y143892D01*
X1320720Y145142D01*
X1319790Y146183D01*
X1318550Y146600D01*
G01X1204005Y116417D02*
X1204935Y117666D01*
X1206020Y118292D01*
X1207260Y118500D01*
X1208810Y118083D01*
X1209895Y117042D01*
X1210205Y115792D01*
X1210050Y114541D01*
X1209430Y113500D01*
X1206330Y111417D01*
X1204935Y109958D01*
X1204005Y107875D01*
X1203695Y106000D01*
X1210205D01*
G01X1216405Y111208D02*
X1217490Y112667D01*
X1218420Y113500D01*
X1219660Y113917D01*
X1220745Y113500D01*
X1221520Y112667D01*
X1222140Y111417D01*
X1222295Y109958D01*
X1222140Y108708D01*
X1221520Y107458D01*
X1220590Y106417D01*
X1219505Y106000D01*
X1218265Y106417D01*
X1217180Y107666D01*
X1216560Y109542D01*
X1216405Y111625D01*
X1216715Y114333D01*
X1217180Y115792D01*
X1217955Y117250D01*
X1219040Y118292D01*
X1220125Y118500D01*
X1221210Y118083D01*
X1221985Y117042D01*
G01X1231750Y106000D02*
X1232835Y106208D01*
X1234075Y106833D01*
X1234850Y107875D01*
X1235160Y109333D01*
X1234850Y110791D01*
X1233920Y112042D01*
X1232525Y112667D01*
X1230975D01*
X1230045Y113083D01*
X1229270Y114125D01*
X1228960Y115583D01*
X1229425Y117042D01*
X1230510Y118083D01*
X1231750Y118500D01*
X1232990Y118083D01*
X1234075Y117042D01*
X1234540Y115583D01*
X1234230Y114125D01*
X1233455Y113083D01*
X1232525Y112667D01*
X1230975D01*
X1229580Y112042D01*
X1228650Y110791D01*
X1228340Y109333D01*
X1228650Y107875D01*
X1229425Y106833D01*
X1230665Y106208D01*
X1231750Y106000D01*
G01X1244150Y105583D02*
X1243840Y105792D01*
Y106208D01*
X1244150Y106417D01*
X1244460Y106208D01*
Y105792D01*
X1244150Y105583D01*
G01X1256550Y118500D02*
X1255310Y118083D01*
X1254380Y117042D01*
X1253760Y115792D01*
X1253295Y114125D01*
X1253140Y112250D01*
X1253295Y110375D01*
X1253760Y108708D01*
X1254380Y107458D01*
X1255310Y106417D01*
X1256550Y106000D01*
X1257790Y106417D01*
X1258720Y107458D01*
X1259340Y108708D01*
X1259805Y110375D01*
X1259960Y112250D01*
X1259805Y114125D01*
X1259340Y115792D01*
X1258720Y117042D01*
X1257790Y118083D01*
X1256550Y118500D01*
G01X1266625Y114333D02*
X1271275Y106000D01*
G01Y114333D02*
X1266625Y106000D01*
G01X1281350D02*
Y118500D01*
X1279490Y116000D01*
G01Y106000D02*
X1283210D01*
G01X1290340Y108500D02*
X1291270Y107041D01*
X1292510Y106208D01*
X1293905Y106000D01*
X1295145Y106208D01*
X1296385Y107250D01*
X1297160Y108500D01*
X1297315Y109750D01*
X1297005Y111208D01*
X1295920Y112250D01*
X1294835Y112667D01*
X1293440D01*
G01X1294835D02*
X1295765Y113292D01*
X1296540Y114333D01*
X1296850Y115583D01*
X1296540Y116833D01*
X1295765Y117875D01*
X1294370Y118500D01*
X1292975Y118292D01*
X1291580Y117458D01*
G01X1308010Y106000D02*
Y118500D01*
X1302275Y109542D01*
X1310025D01*
G01X1318550Y105583D02*
X1318240Y105792D01*
Y106208D01*
X1318550Y106417D01*
X1318860Y106208D01*
Y105792D01*
X1318550Y105583D01*
G01X1330950Y118500D02*
X1329710Y118083D01*
X1328780Y117042D01*
X1328160Y115792D01*
X1327695Y114125D01*
X1327540Y112250D01*
X1327695Y110375D01*
X1328160Y108708D01*
X1328780Y107458D01*
X1329710Y106417D01*
X1330950Y106000D01*
X1332190Y106417D01*
X1333120Y107458D01*
X1333740Y108708D01*
X1334205Y110375D01*
X1334360Y112250D01*
X1334205Y114125D01*
X1333740Y115792D01*
X1333120Y117042D01*
X1332190Y118083D01*
X1330950Y118500D01*
G01X1244150Y190300D02*
Y202800D01*
X1242290Y200300D01*
G01Y190300D02*
X1246010D01*
G01X1253140Y192800D02*
X1254070Y191341D01*
X1255310Y190508D01*
X1256705Y190300D01*
X1257945Y190508D01*
X1259185Y191550D01*
X1259960Y192800D01*
X1260115Y194050D01*
X1259805Y195508D01*
X1258720Y196550D01*
X1257635Y196967D01*
X1256240D01*
G01X1257635D02*
X1258565Y197592D01*
X1259340Y198633D01*
X1259650Y199883D01*
X1259340Y201133D01*
X1258565Y202175D01*
X1257170Y202800D01*
X1255775Y202592D01*
X1254380Y201758D01*
G01X1268950Y202800D02*
X1267710Y202383D01*
X1266780Y201342D01*
X1266160Y200092D01*
X1265695Y198425D01*
X1265540Y196550D01*
X1265695Y194675D01*
X1266160Y193008D01*
X1266780Y191758D01*
X1267710Y190717D01*
X1268950Y190300D01*
X1270190Y190717D01*
X1271120Y191758D01*
X1271740Y193008D01*
X1272205Y194675D01*
X1272360Y196550D01*
X1272205Y198425D01*
X1271740Y200092D01*
X1271120Y201342D01*
X1270190Y202383D01*
X1268950Y202800D01*
G01X1281350Y189883D02*
X1281040Y190092D01*
Y190508D01*
X1281350Y190717D01*
X1281660Y190508D01*
Y190092D01*
X1281350Y189883D01*
G01X1293750Y202800D02*
X1292510Y202383D01*
X1291580Y201342D01*
X1290960Y200092D01*
X1290495Y198425D01*
X1290340Y196550D01*
X1290495Y194675D01*
X1290960Y193008D01*
X1291580Y191758D01*
X1292510Y190717D01*
X1293750Y190300D01*
X1294990Y190717D01*
X1295920Y191758D01*
X1296540Y193008D01*
X1297005Y194675D01*
X1297160Y196550D01*
X1297005Y198425D01*
X1296540Y200092D01*
X1295920Y201342D01*
X1294990Y202383D01*
X1293750Y202800D01*
G01X1215940Y164075D02*
X1216870Y163033D01*
X1217955Y162408D01*
X1219350Y162200D01*
X1220745Y162617D01*
X1221830Y163450D01*
X1222605Y164908D01*
X1222760Y166575D01*
X1222450Y168242D01*
X1221675Y169283D01*
X1220590Y170117D01*
X1219505Y170325D01*
X1218420Y170117D01*
X1217025Y169283D01*
X1217490Y174700D01*
X1221675D01*
G01X1228805Y167408D02*
X1229890Y168867D01*
X1230820Y169700D01*
X1232060Y170117D01*
X1233145Y169700D01*
X1233920Y168867D01*
X1234540Y167617D01*
X1234695Y166158D01*
X1234540Y164908D01*
X1233920Y163658D01*
X1232990Y162617D01*
X1231905Y162200D01*
X1230665Y162617D01*
X1229580Y163866D01*
X1228960Y165742D01*
X1228805Y167825D01*
X1229115Y170533D01*
X1229580Y171992D01*
X1230355Y173450D01*
X1231440Y174492D01*
X1232525Y174700D01*
X1233610Y174283D01*
X1234385Y173242D01*
G01X1244150Y161783D02*
X1243840Y161992D01*
Y162408D01*
X1244150Y162617D01*
X1244460Y162408D01*
Y161992D01*
X1244150Y161783D01*
G01X1256550Y174700D02*
X1255310Y174283D01*
X1254380Y173242D01*
X1253760Y171992D01*
X1253295Y170325D01*
X1253140Y168450D01*
X1253295Y166575D01*
X1253760Y164908D01*
X1254380Y163658D01*
X1255310Y162617D01*
X1256550Y162200D01*
X1257790Y162617D01*
X1258720Y163658D01*
X1259340Y164908D01*
X1259805Y166575D01*
X1259960Y168450D01*
X1259805Y170325D01*
X1259340Y171992D01*
X1258720Y173242D01*
X1257790Y174283D01*
X1256550Y174700D01*
G01X1266625Y170533D02*
X1271275Y162200D01*
G01Y170533D02*
X1266625Y162200D01*
G01X1277940Y164700D02*
X1278870Y163241D01*
X1280110Y162408D01*
X1281505Y162200D01*
X1282745Y162408D01*
X1283985Y163450D01*
X1284760Y164700D01*
X1284915Y165950D01*
X1284605Y167408D01*
X1283520Y168450D01*
X1282435Y168867D01*
X1281040D01*
G01X1282435D02*
X1283365Y169492D01*
X1284140Y170533D01*
X1284450Y171783D01*
X1284140Y173033D01*
X1283365Y174075D01*
X1281970Y174700D01*
X1280575Y174492D01*
X1279180Y173658D01*
G01X1290805Y172617D02*
X1291735Y173866D01*
X1292820Y174492D01*
X1294060Y174700D01*
X1295610Y174283D01*
X1296695Y173242D01*
X1297005Y171992D01*
X1296850Y170741D01*
X1296230Y169700D01*
X1293130Y167617D01*
X1291735Y166158D01*
X1290805Y164075D01*
X1290495Y162200D01*
X1297005D01*
G01X1306150Y161783D02*
X1305840Y161992D01*
Y162408D01*
X1306150Y162617D01*
X1306460Y162408D01*
Y161992D01*
X1306150Y161783D01*
G01X1318550Y174700D02*
X1317310Y174283D01*
X1316380Y173242D01*
X1315760Y171992D01*
X1315295Y170325D01*
X1315140Y168450D01*
X1315295Y166575D01*
X1315760Y164908D01*
X1316380Y163658D01*
X1317310Y162617D01*
X1318550Y162200D01*
X1319790Y162617D01*
X1320720Y163658D01*
X1321340Y164908D01*
X1321805Y166575D01*
X1321960Y168450D01*
X1321805Y170325D01*
X1321340Y171992D01*
X1320720Y173242D01*
X1319790Y174283D01*
X1318550Y174700D01*
G01X1247715Y247958D02*
X1248800Y246917D01*
X1250040Y246500D01*
X1251280Y246917D01*
X1252365Y248166D01*
X1253140Y250042D01*
X1253450Y251917D01*
Y254208D01*
X1253140Y256083D01*
X1252365Y257750D01*
X1251435Y258583D01*
X1250350Y259000D01*
X1249110Y258583D01*
X1248180Y257750D01*
X1247560Y256500D01*
X1247250Y254833D01*
X1247560Y253375D01*
X1248335Y251917D01*
X1249265Y251083D01*
X1250350Y250875D01*
X1251590Y251291D01*
X1252520Y252333D01*
X1253450Y254208D01*
G01X1262440Y246500D02*
X1262750Y249208D01*
X1263215Y251500D01*
X1263835Y253583D01*
X1264610Y255875D01*
X1265850Y259000D01*
X1259650D01*
G01X1275150Y246083D02*
X1274840Y246292D01*
Y246708D01*
X1275150Y246917D01*
X1275460Y246708D01*
Y246292D01*
X1275150Y246083D01*
G01X1287550Y259000D02*
X1286310Y258583D01*
X1285380Y257542D01*
X1284760Y256292D01*
X1284295Y254625D01*
X1284140Y252750D01*
X1284295Y250875D01*
X1284760Y249208D01*
X1285380Y247958D01*
X1286310Y246917D01*
X1287550Y246500D01*
X1288790Y246917D01*
X1289720Y247958D01*
X1290340Y249208D01*
X1290805Y250875D01*
X1290960Y252750D01*
X1290805Y254625D01*
X1290340Y256292D01*
X1289720Y257542D01*
X1288790Y258583D01*
X1287550Y259000D01*
G01X1244150Y218400D02*
Y230900D01*
X1242290Y228400D01*
G01Y218400D02*
X1246010D01*
G01X1256550D02*
Y230900D01*
X1254690Y228400D01*
G01Y218400D02*
X1258410D01*
G01X1266315Y219858D02*
X1267400Y218817D01*
X1268640Y218400D01*
X1269880Y218817D01*
X1270965Y220066D01*
X1271740Y221942D01*
X1272050Y223817D01*
Y226108D01*
X1271740Y227983D01*
X1270965Y229650D01*
X1270035Y230483D01*
X1268950Y230900D01*
X1267710Y230483D01*
X1266780Y229650D01*
X1266160Y228400D01*
X1265850Y226733D01*
X1266160Y225275D01*
X1266935Y223817D01*
X1267865Y222983D01*
X1268950Y222775D01*
X1270190Y223191D01*
X1271120Y224233D01*
X1272050Y226108D01*
G01X1281350Y217983D02*
X1281040Y218192D01*
Y218608D01*
X1281350Y218817D01*
X1281660Y218608D01*
Y218192D01*
X1281350Y217983D01*
G01X1293750Y230900D02*
X1292510Y230483D01*
X1291580Y229442D01*
X1290960Y228192D01*
X1290495Y226525D01*
X1290340Y224650D01*
X1290495Y222775D01*
X1290960Y221108D01*
X1291580Y219858D01*
X1292510Y218817D01*
X1293750Y218400D01*
X1294990Y218817D01*
X1295920Y219858D01*
X1296540Y221108D01*
X1297005Y222775D01*
X1297160Y224650D01*
X1297005Y226525D01*
X1296540Y228192D01*
X1295920Y229442D01*
X1294990Y230483D01*
X1293750Y230900D01*
G01X1252210Y330800D02*
Y343300D01*
X1246475Y334342D01*
X1254225D01*
G01X1262750Y330800D02*
X1263835Y331008D01*
X1265075Y331633D01*
X1265850Y332675D01*
X1266160Y334133D01*
X1265850Y335591D01*
X1264920Y336842D01*
X1263525Y337467D01*
X1261975D01*
X1261045Y337883D01*
X1260270Y338925D01*
X1259960Y340383D01*
X1260425Y341842D01*
X1261510Y342883D01*
X1262750Y343300D01*
X1263990Y342883D01*
X1265075Y341842D01*
X1265540Y340383D01*
X1265230Y338925D01*
X1264455Y337883D01*
X1263525Y337467D01*
X1261975D01*
X1260580Y336842D01*
X1259650Y335591D01*
X1259340Y334133D01*
X1259650Y332675D01*
X1260425Y331633D01*
X1261665Y331008D01*
X1262750Y330800D01*
G01X1275150Y330383D02*
X1274840Y330592D01*
Y331008D01*
X1275150Y331217D01*
X1275460Y331008D01*
Y330592D01*
X1275150Y330383D01*
G01X1287550Y343300D02*
X1286310Y342883D01*
X1285380Y341842D01*
X1284760Y340592D01*
X1284295Y338925D01*
X1284140Y337050D01*
X1284295Y335175D01*
X1284760Y333508D01*
X1285380Y332258D01*
X1286310Y331217D01*
X1287550Y330800D01*
X1288790Y331217D01*
X1289720Y332258D01*
X1290340Y333508D01*
X1290805Y335175D01*
X1290960Y337050D01*
X1290805Y338925D01*
X1290340Y340592D01*
X1289720Y341842D01*
X1288790Y342883D01*
X1287550Y343300D01*
G01X1250350Y302700D02*
X1251435Y302908D01*
X1252675Y303533D01*
X1253450Y304575D01*
X1253760Y306033D01*
X1253450Y307491D01*
X1252520Y308742D01*
X1251125Y309367D01*
X1249575D01*
X1248645Y309783D01*
X1247870Y310825D01*
X1247560Y312283D01*
X1248025Y313742D01*
X1249110Y314783D01*
X1250350Y315200D01*
X1251590Y314783D01*
X1252675Y313742D01*
X1253140Y312283D01*
X1252830Y310825D01*
X1252055Y309783D01*
X1251125Y309367D01*
X1249575D01*
X1248180Y308742D01*
X1247250Y307491D01*
X1246940Y306033D01*
X1247250Y304575D01*
X1248025Y303533D01*
X1249265Y302908D01*
X1250350Y302700D01*
G01X1259805Y307908D02*
X1260890Y309367D01*
X1261820Y310200D01*
X1263060Y310617D01*
X1264145Y310200D01*
X1264920Y309367D01*
X1265540Y308117D01*
X1265695Y306658D01*
X1265540Y305408D01*
X1264920Y304158D01*
X1263990Y303117D01*
X1262905Y302700D01*
X1261665Y303117D01*
X1260580Y304366D01*
X1259960Y306242D01*
X1259805Y308325D01*
X1260115Y311033D01*
X1260580Y312492D01*
X1261355Y313950D01*
X1262440Y314992D01*
X1263525Y315200D01*
X1264610Y314783D01*
X1265385Y313742D01*
G01X1275150Y302283D02*
X1274840Y302492D01*
Y302908D01*
X1275150Y303117D01*
X1275460Y302908D01*
Y302492D01*
X1275150Y302283D01*
G01X1287550Y315200D02*
X1286310Y314783D01*
X1285380Y313742D01*
X1284760Y312492D01*
X1284295Y310825D01*
X1284140Y308950D01*
X1284295Y307075D01*
X1284760Y305408D01*
X1285380Y304158D01*
X1286310Y303117D01*
X1287550Y302700D01*
X1288790Y303117D01*
X1289720Y304158D01*
X1290340Y305408D01*
X1290805Y307075D01*
X1290960Y308950D01*
X1290805Y310825D01*
X1290340Y312492D01*
X1289720Y313742D01*
X1288790Y314783D01*
X1287550Y315200D01*
G01X1247715Y276058D02*
X1248800Y275017D01*
X1250040Y274600D01*
X1251280Y275017D01*
X1252365Y276266D01*
X1253140Y278142D01*
X1253450Y280017D01*
Y282308D01*
X1253140Y284183D01*
X1252365Y285850D01*
X1251435Y286683D01*
X1250350Y287100D01*
X1249110Y286683D01*
X1248180Y285850D01*
X1247560Y284600D01*
X1247250Y282933D01*
X1247560Y281475D01*
X1248335Y280017D01*
X1249265Y279183D01*
X1250350Y278975D01*
X1251590Y279391D01*
X1252520Y280433D01*
X1253450Y282308D01*
G01X1264610Y274600D02*
Y287100D01*
X1258875Y278142D01*
X1266625D01*
G01X1275150Y274183D02*
X1274840Y274392D01*
Y274808D01*
X1275150Y275017D01*
X1275460Y274808D01*
Y274392D01*
X1275150Y274183D01*
G01X1287550Y287100D02*
X1286310Y286683D01*
X1285380Y285642D01*
X1284760Y284392D01*
X1284295Y282725D01*
X1284140Y280850D01*
X1284295Y278975D01*
X1284760Y277308D01*
X1285380Y276058D01*
X1286310Y275017D01*
X1287550Y274600D01*
X1288790Y275017D01*
X1289720Y276058D01*
X1290340Y277308D01*
X1290805Y278975D01*
X1290960Y280850D01*
X1290805Y282725D01*
X1290340Y284392D01*
X1289720Y285642D01*
X1288790Y286683D01*
X1287550Y287100D01*
G01X1246940Y389500D02*
X1247870Y388041D01*
X1249110Y387208D01*
X1250505Y387000D01*
X1251745Y387208D01*
X1252985Y388250D01*
X1253760Y389500D01*
X1253915Y390750D01*
X1253605Y392208D01*
X1252520Y393250D01*
X1251435Y393667D01*
X1250040D01*
G01X1251435D02*
X1252365Y394292D01*
X1253140Y395333D01*
X1253450Y396583D01*
X1253140Y397833D01*
X1252365Y398875D01*
X1250970Y399500D01*
X1249575Y399292D01*
X1248180Y398458D01*
G01X1259805Y397417D02*
X1260735Y398666D01*
X1261820Y399292D01*
X1263060Y399500D01*
X1264610Y399083D01*
X1265695Y398042D01*
X1266005Y396792D01*
X1265850Y395541D01*
X1265230Y394500D01*
X1262130Y392417D01*
X1260735Y390958D01*
X1259805Y388875D01*
X1259495Y387000D01*
X1266005D01*
G01X1275150Y386583D02*
X1274840Y386792D01*
Y387208D01*
X1275150Y387417D01*
X1275460Y387208D01*
Y386792D01*
X1275150Y386583D01*
G01X1287550Y399500D02*
X1286310Y399083D01*
X1285380Y398042D01*
X1284760Y396792D01*
X1284295Y395125D01*
X1284140Y393250D01*
X1284295Y391375D01*
X1284760Y389708D01*
X1285380Y388458D01*
X1286310Y387417D01*
X1287550Y387000D01*
X1288790Y387417D01*
X1289720Y388458D01*
X1290340Y389708D01*
X1290805Y391375D01*
X1290960Y393250D01*
X1290805Y395125D01*
X1290340Y396792D01*
X1289720Y398042D01*
X1288790Y399083D01*
X1287550Y399500D01*
G01X1246940Y361400D02*
X1247870Y359941D01*
X1249110Y359108D01*
X1250505Y358900D01*
X1251745Y359108D01*
X1252985Y360150D01*
X1253760Y361400D01*
X1253915Y362650D01*
X1253605Y364108D01*
X1252520Y365150D01*
X1251435Y365567D01*
X1250040D01*
G01X1251435D02*
X1252365Y366192D01*
X1253140Y367233D01*
X1253450Y368483D01*
X1253140Y369733D01*
X1252365Y370775D01*
X1250970Y371400D01*
X1249575Y371192D01*
X1248180Y370358D01*
G01X1264610Y358900D02*
Y371400D01*
X1258875Y362442D01*
X1266625D01*
G01X1275150Y358483D02*
X1274840Y358692D01*
Y359108D01*
X1275150Y359317D01*
X1275460Y359108D01*
Y358692D01*
X1275150Y358483D01*
G01X1287550Y371400D02*
X1286310Y370983D01*
X1285380Y369942D01*
X1284760Y368692D01*
X1284295Y367025D01*
X1284140Y365150D01*
X1284295Y363275D01*
X1284760Y361608D01*
X1285380Y360358D01*
X1286310Y359317D01*
X1287550Y358900D01*
X1288790Y359317D01*
X1289720Y360358D01*
X1290340Y361608D01*
X1290805Y363275D01*
X1290960Y365150D01*
X1290805Y367025D01*
X1290340Y368692D01*
X1289720Y369942D01*
X1288790Y370983D01*
X1287550Y371400D01*
G01X1244150Y443200D02*
Y455700D01*
X1242290Y453200D01*
G01Y443200D02*
X1246010D01*
G01X1253140Y445075D02*
X1254070Y444033D01*
X1255155Y443408D01*
X1256550Y443200D01*
X1257945Y443617D01*
X1259030Y444450D01*
X1259805Y445908D01*
X1259960Y447575D01*
X1259650Y449242D01*
X1258875Y450283D01*
X1257790Y451117D01*
X1256705Y451325D01*
X1255620Y451117D01*
X1254225Y450283D01*
X1254690Y455700D01*
X1258875D01*
G01X1268950Y443200D02*
X1270035Y443408D01*
X1271275Y444033D01*
X1272050Y445075D01*
X1272360Y446533D01*
X1272050Y447991D01*
X1271120Y449242D01*
X1269725Y449867D01*
X1268175D01*
X1267245Y450283D01*
X1266470Y451325D01*
X1266160Y452783D01*
X1266625Y454242D01*
X1267710Y455283D01*
X1268950Y455700D01*
X1270190Y455283D01*
X1271275Y454242D01*
X1271740Y452783D01*
X1271430Y451325D01*
X1270655Y450283D01*
X1269725Y449867D01*
X1268175D01*
X1266780Y449242D01*
X1265850Y447991D01*
X1265540Y446533D01*
X1265850Y445075D01*
X1266625Y444033D01*
X1267865Y443408D01*
X1268950Y443200D01*
G01X1281350Y442783D02*
X1281040Y442992D01*
Y443408D01*
X1281350Y443617D01*
X1281660Y443408D01*
Y442992D01*
X1281350Y442783D01*
G01X1293750Y455700D02*
X1292510Y455283D01*
X1291580Y454242D01*
X1290960Y452992D01*
X1290495Y451325D01*
X1290340Y449450D01*
X1290495Y447575D01*
X1290960Y445908D01*
X1291580Y444658D01*
X1292510Y443617D01*
X1293750Y443200D01*
X1294990Y443617D01*
X1295920Y444658D01*
X1296540Y445908D01*
X1297005Y447575D01*
X1297160Y449450D01*
X1297005Y451325D01*
X1296540Y452992D01*
X1295920Y454242D01*
X1294990Y455283D01*
X1293750Y455700D01*
G01X1244150Y415100D02*
Y427600D01*
X1242290Y425100D01*
G01Y415100D02*
X1246010D01*
G01X1253605Y420308D02*
X1254690Y421767D01*
X1255620Y422600D01*
X1256860Y423017D01*
X1257945Y422600D01*
X1258720Y421767D01*
X1259340Y420517D01*
X1259495Y419058D01*
X1259340Y417808D01*
X1258720Y416558D01*
X1257790Y415517D01*
X1256705Y415100D01*
X1255465Y415517D01*
X1254380Y416766D01*
X1253760Y418642D01*
X1253605Y420725D01*
X1253915Y423433D01*
X1254380Y424892D01*
X1255155Y426350D01*
X1256240Y427392D01*
X1257325Y427600D01*
X1258410Y427183D01*
X1259185Y426142D01*
G01X1268950Y415100D02*
X1270035Y415308D01*
X1271275Y415933D01*
X1272050Y416975D01*
X1272360Y418433D01*
X1272050Y419891D01*
X1271120Y421142D01*
X1269725Y421767D01*
X1268175D01*
X1267245Y422183D01*
X1266470Y423225D01*
X1266160Y424683D01*
X1266625Y426142D01*
X1267710Y427183D01*
X1268950Y427600D01*
X1270190Y427183D01*
X1271275Y426142D01*
X1271740Y424683D01*
X1271430Y423225D01*
X1270655Y422183D01*
X1269725Y421767D01*
X1268175D01*
X1266780Y421142D01*
X1265850Y419891D01*
X1265540Y418433D01*
X1265850Y416975D01*
X1266625Y415933D01*
X1267865Y415308D01*
X1268950Y415100D01*
G01X1281350Y414683D02*
X1281040Y414892D01*
Y415308D01*
X1281350Y415517D01*
X1281660Y415308D01*
Y414892D01*
X1281350Y414683D01*
G01X1293750Y427600D02*
X1292510Y427183D01*
X1291580Y426142D01*
X1290960Y424892D01*
X1290495Y423225D01*
X1290340Y421350D01*
X1290495Y419475D01*
X1290960Y417808D01*
X1291580Y416558D01*
X1292510Y415517D01*
X1293750Y415100D01*
X1294990Y415517D01*
X1295920Y416558D01*
X1296540Y417808D01*
X1297005Y419475D01*
X1297160Y421350D01*
X1297005Y423225D01*
X1296540Y424892D01*
X1295920Y426142D01*
X1294990Y427183D01*
X1293750Y427600D01*
G01X1252210Y527500D02*
Y540000D01*
X1246475Y531042D01*
X1254225D01*
G01X1262750Y540000D02*
X1261510Y539583D01*
X1260580Y538542D01*
X1259960Y537292D01*
X1259495Y535625D01*
X1259340Y533750D01*
X1259495Y531875D01*
X1259960Y530208D01*
X1260580Y528958D01*
X1261510Y527917D01*
X1262750Y527500D01*
X1263990Y527917D01*
X1264920Y528958D01*
X1265540Y530208D01*
X1266005Y531875D01*
X1266160Y533750D01*
X1266005Y535625D01*
X1265540Y537292D01*
X1264920Y538542D01*
X1263990Y539583D01*
X1262750Y540000D01*
G01X1275150Y527083D02*
X1274840Y527292D01*
Y527708D01*
X1275150Y527917D01*
X1275460Y527708D01*
Y527292D01*
X1275150Y527083D01*
G01X1287550Y540000D02*
X1286310Y539583D01*
X1285380Y538542D01*
X1284760Y537292D01*
X1284295Y535625D01*
X1284140Y533750D01*
X1284295Y531875D01*
X1284760Y530208D01*
X1285380Y528958D01*
X1286310Y527917D01*
X1287550Y527500D01*
X1288790Y527917D01*
X1289720Y528958D01*
X1290340Y530208D01*
X1290805Y531875D01*
X1290960Y533750D01*
X1290805Y535625D01*
X1290340Y537292D01*
X1289720Y538542D01*
X1288790Y539583D01*
X1287550Y540000D01*
G01X1250350Y499400D02*
X1251435Y499608D01*
X1252675Y500233D01*
X1253450Y501275D01*
X1253760Y502733D01*
X1253450Y504191D01*
X1252520Y505442D01*
X1251125Y506067D01*
X1249575D01*
X1248645Y506483D01*
X1247870Y507525D01*
X1247560Y508983D01*
X1248025Y510442D01*
X1249110Y511483D01*
X1250350Y511900D01*
X1251590Y511483D01*
X1252675Y510442D01*
X1253140Y508983D01*
X1252830Y507525D01*
X1252055Y506483D01*
X1251125Y506067D01*
X1249575D01*
X1248180Y505442D01*
X1247250Y504191D01*
X1246940Y502733D01*
X1247250Y501275D01*
X1248025Y500233D01*
X1249265Y499608D01*
X1250350Y499400D01*
G01X1262440D02*
X1262750Y502108D01*
X1263215Y504400D01*
X1263835Y506483D01*
X1264610Y508775D01*
X1265850Y511900D01*
X1259650D01*
G01X1275150Y498983D02*
X1274840Y499192D01*
Y499608D01*
X1275150Y499817D01*
X1275460Y499608D01*
Y499192D01*
X1275150Y498983D01*
G01X1287550Y511900D02*
X1286310Y511483D01*
X1285380Y510442D01*
X1284760Y509192D01*
X1284295Y507525D01*
X1284140Y505650D01*
X1284295Y503775D01*
X1284760Y502108D01*
X1285380Y500858D01*
X1286310Y499817D01*
X1287550Y499400D01*
X1288790Y499817D01*
X1289720Y500858D01*
X1290340Y502108D01*
X1290805Y503775D01*
X1290960Y505650D01*
X1290805Y507525D01*
X1290340Y509192D01*
X1289720Y510442D01*
X1288790Y511483D01*
X1287550Y511900D01*
G01X1244150Y471300D02*
Y483800D01*
X1242290Y481300D01*
G01Y471300D02*
X1246010D01*
G01X1253140Y473800D02*
X1254070Y472341D01*
X1255310Y471508D01*
X1256705Y471300D01*
X1257945Y471508D01*
X1259185Y472550D01*
X1259960Y473800D01*
X1260115Y475050D01*
X1259805Y476508D01*
X1258720Y477550D01*
X1257635Y477967D01*
X1256240D01*
G01X1257635D02*
X1258565Y478592D01*
X1259340Y479633D01*
X1259650Y480883D01*
X1259340Y482133D01*
X1258565Y483175D01*
X1257170Y483800D01*
X1255775Y483592D01*
X1254380Y482758D01*
G01X1268950Y471300D02*
X1270035Y471508D01*
X1271275Y472133D01*
X1272050Y473175D01*
X1272360Y474633D01*
X1272050Y476091D01*
X1271120Y477342D01*
X1269725Y477967D01*
X1268175D01*
X1267245Y478383D01*
X1266470Y479425D01*
X1266160Y480883D01*
X1266625Y482342D01*
X1267710Y483383D01*
X1268950Y483800D01*
X1270190Y483383D01*
X1271275Y482342D01*
X1271740Y480883D01*
X1271430Y479425D01*
X1270655Y478383D01*
X1269725Y477967D01*
X1268175D01*
X1266780Y477342D01*
X1265850Y476091D01*
X1265540Y474633D01*
X1265850Y473175D01*
X1266625Y472133D01*
X1267865Y471508D01*
X1268950Y471300D01*
G01X1281350Y470883D02*
X1281040Y471092D01*
Y471508D01*
X1281350Y471717D01*
X1281660Y471508D01*
Y471092D01*
X1281350Y470883D01*
G01X1293750Y483800D02*
X1292510Y483383D01*
X1291580Y482342D01*
X1290960Y481092D01*
X1290495Y479425D01*
X1290340Y477550D01*
X1290495Y475675D01*
X1290960Y474008D01*
X1291580Y472758D01*
X1292510Y471717D01*
X1293750Y471300D01*
X1294990Y471717D01*
X1295920Y472758D01*
X1296540Y474008D01*
X1297005Y475675D01*
X1297160Y477550D01*
X1297005Y479425D01*
X1296540Y481092D01*
X1295920Y482342D01*
X1294990Y483383D01*
X1293750Y483800D01*
G01X1247405Y594117D02*
X1248335Y595366D01*
X1249420Y595992D01*
X1250660Y596200D01*
X1252210Y595783D01*
X1253295Y594742D01*
X1253605Y593492D01*
X1253450Y592241D01*
X1252830Y591200D01*
X1249730Y589117D01*
X1248335Y587658D01*
X1247405Y585575D01*
X1247095Y583700D01*
X1253605D01*
G01X1262750D02*
X1263835Y583908D01*
X1265075Y584533D01*
X1265850Y585575D01*
X1266160Y587033D01*
X1265850Y588491D01*
X1264920Y589742D01*
X1263525Y590367D01*
X1261975D01*
X1261045Y590783D01*
X1260270Y591825D01*
X1259960Y593283D01*
X1260425Y594742D01*
X1261510Y595783D01*
X1262750Y596200D01*
X1263990Y595783D01*
X1265075Y594742D01*
X1265540Y593283D01*
X1265230Y591825D01*
X1264455Y590783D01*
X1263525Y590367D01*
X1261975D01*
X1260580Y589742D01*
X1259650Y588491D01*
X1259340Y587033D01*
X1259650Y585575D01*
X1260425Y584533D01*
X1261665Y583908D01*
X1262750Y583700D01*
G01X1275150Y583283D02*
X1274840Y583492D01*
Y583908D01*
X1275150Y584117D01*
X1275460Y583908D01*
Y583492D01*
X1275150Y583283D01*
G01X1287550Y596200D02*
X1286310Y595783D01*
X1285380Y594742D01*
X1284760Y593492D01*
X1284295Y591825D01*
X1284140Y589950D01*
X1284295Y588075D01*
X1284760Y586408D01*
X1285380Y585158D01*
X1286310Y584117D01*
X1287550Y583700D01*
X1288790Y584117D01*
X1289720Y585158D01*
X1290340Y586408D01*
X1290805Y588075D01*
X1290960Y589950D01*
X1290805Y591825D01*
X1290340Y593492D01*
X1289720Y594742D01*
X1288790Y595783D01*
X1287550Y596200D01*
G01X1246940Y558100D02*
X1247870Y556641D01*
X1249110Y555808D01*
X1250505Y555600D01*
X1251745Y555808D01*
X1252985Y556850D01*
X1253760Y558100D01*
X1253915Y559350D01*
X1253605Y560808D01*
X1252520Y561850D01*
X1251435Y562267D01*
X1250040D01*
G01X1251435D02*
X1252365Y562892D01*
X1253140Y563933D01*
X1253450Y565183D01*
X1253140Y566433D01*
X1252365Y567475D01*
X1250970Y568100D01*
X1249575Y567892D01*
X1248180Y567058D01*
G01X1259340Y557475D02*
X1260270Y556433D01*
X1261355Y555808D01*
X1262750Y555600D01*
X1264145Y556017D01*
X1265230Y556850D01*
X1266005Y558308D01*
X1266160Y559975D01*
X1265850Y561642D01*
X1265075Y562683D01*
X1263990Y563517D01*
X1262905Y563725D01*
X1261820Y563517D01*
X1260425Y562683D01*
X1260890Y568100D01*
X1265075D01*
G01X1275150Y555183D02*
X1274840Y555392D01*
Y555808D01*
X1275150Y556017D01*
X1275460Y555808D01*
Y555392D01*
X1275150Y555183D01*
G01X1287550Y568100D02*
X1286310Y567683D01*
X1285380Y566642D01*
X1284760Y565392D01*
X1284295Y563725D01*
X1284140Y561850D01*
X1284295Y559975D01*
X1284760Y558308D01*
X1285380Y557058D01*
X1286310Y556017D01*
X1287550Y555600D01*
X1288790Y556017D01*
X1289720Y557058D01*
X1290340Y558308D01*
X1290805Y559975D01*
X1290960Y561850D01*
X1290805Y563725D01*
X1290340Y565392D01*
X1289720Y566642D01*
X1288790Y567683D01*
X1287550Y568100D01*
G01X1250350Y639900D02*
Y652400D01*
X1248490Y649900D01*
G01Y639900D02*
X1252210D01*
G01X1259805Y645108D02*
X1260890Y646567D01*
X1261820Y647400D01*
X1263060Y647817D01*
X1264145Y647400D01*
X1264920Y646567D01*
X1265540Y645317D01*
X1265695Y643858D01*
X1265540Y642608D01*
X1264920Y641358D01*
X1263990Y640317D01*
X1262905Y639900D01*
X1261665Y640317D01*
X1260580Y641566D01*
X1259960Y643442D01*
X1259805Y645525D01*
X1260115Y648233D01*
X1260580Y649692D01*
X1261355Y651150D01*
X1262440Y652192D01*
X1263525Y652400D01*
X1264610Y651983D01*
X1265385Y650942D01*
G01X1275150Y639483D02*
X1274840Y639692D01*
Y640108D01*
X1275150Y640317D01*
X1275460Y640108D01*
Y639692D01*
X1275150Y639483D01*
G01X1287550Y652400D02*
X1286310Y651983D01*
X1285380Y650942D01*
X1284760Y649692D01*
X1284295Y648025D01*
X1284140Y646150D01*
X1284295Y644275D01*
X1284760Y642608D01*
X1285380Y641358D01*
X1286310Y640317D01*
X1287550Y639900D01*
X1288790Y640317D01*
X1289720Y641358D01*
X1290340Y642608D01*
X1290805Y644275D01*
X1290960Y646150D01*
X1290805Y648025D01*
X1290340Y649692D01*
X1289720Y650942D01*
X1288790Y651983D01*
X1287550Y652400D01*
G01X1241205Y622217D02*
X1242135Y623466D01*
X1243220Y624092D01*
X1244460Y624300D01*
X1246010Y623883D01*
X1247095Y622842D01*
X1247405Y621592D01*
X1247250Y620341D01*
X1246630Y619300D01*
X1243530Y617217D01*
X1242135Y615758D01*
X1241205Y613675D01*
X1240895Y611800D01*
X1247405D01*
G01X1253605Y622217D02*
X1254535Y623466D01*
X1255620Y624092D01*
X1256860Y624300D01*
X1258410Y623883D01*
X1259495Y622842D01*
X1259805Y621592D01*
X1259650Y620341D01*
X1259030Y619300D01*
X1255930Y617217D01*
X1254535Y615758D01*
X1253605Y613675D01*
X1253295Y611800D01*
X1259805D01*
G01X1268950Y611383D02*
X1268640Y611592D01*
Y612008D01*
X1268950Y612217D01*
X1269260Y612008D01*
Y611592D01*
X1268950Y611383D01*
G01X1283210Y611800D02*
Y624300D01*
X1277475Y615342D01*
X1285225D01*
G01X1295610Y611800D02*
Y624300D01*
X1289875Y615342D01*
X1297625D01*
G01X1250350Y724200D02*
Y736700D01*
X1248490Y734200D01*
G01Y724200D02*
X1252210D01*
G01X1259805Y734617D02*
X1260735Y735866D01*
X1261820Y736492D01*
X1263060Y736700D01*
X1264610Y736283D01*
X1265695Y735242D01*
X1266005Y733992D01*
X1265850Y732741D01*
X1265230Y731700D01*
X1262130Y729617D01*
X1260735Y728158D01*
X1259805Y726075D01*
X1259495Y724200D01*
X1266005D01*
G01X1275150Y723783D02*
X1274840Y723992D01*
Y724408D01*
X1275150Y724617D01*
X1275460Y724408D01*
Y723992D01*
X1275150Y723783D01*
G01X1287550Y736700D02*
X1286310Y736283D01*
X1285380Y735242D01*
X1284760Y733992D01*
X1284295Y732325D01*
X1284140Y730450D01*
X1284295Y728575D01*
X1284760Y726908D01*
X1285380Y725658D01*
X1286310Y724617D01*
X1287550Y724200D01*
X1288790Y724617D01*
X1289720Y725658D01*
X1290340Y726908D01*
X1290805Y728575D01*
X1290960Y730450D01*
X1290805Y732325D01*
X1290340Y733992D01*
X1289720Y735242D01*
X1288790Y736283D01*
X1287550Y736700D01*
G01X1244150Y696100D02*
Y708600D01*
X1242290Y706100D01*
G01Y696100D02*
X1246010D01*
G01X1258410D02*
Y708600D01*
X1252675Y699642D01*
X1260425D01*
G01X1268950Y695683D02*
X1268640Y695892D01*
Y696308D01*
X1268950Y696517D01*
X1269260Y696308D01*
Y695892D01*
X1268950Y695683D01*
G01X1281350Y696100D02*
Y708600D01*
X1279490Y706100D01*
G01Y696100D02*
X1283210D01*
G01X1293440D02*
X1293750Y698808D01*
X1294215Y701100D01*
X1294835Y703183D01*
X1295610Y705475D01*
X1296850Y708600D01*
X1290650D01*
G01X1244150Y668000D02*
Y680500D01*
X1242290Y678000D01*
G01Y668000D02*
X1246010D01*
G01X1258410D02*
Y680500D01*
X1252675Y671542D01*
X1260425D01*
G01X1268950Y667583D02*
X1268640Y667792D01*
Y668208D01*
X1268950Y668417D01*
X1269260Y668208D01*
Y667792D01*
X1268950Y667583D01*
G01X1277940Y669875D02*
X1278870Y668833D01*
X1279955Y668208D01*
X1281350Y668000D01*
X1282745Y668417D01*
X1283830Y669250D01*
X1284605Y670708D01*
X1284760Y672375D01*
X1284450Y674042D01*
X1283675Y675083D01*
X1282590Y675917D01*
X1281505Y676125D01*
X1280420Y675917D01*
X1279025Y675083D01*
X1279490Y680500D01*
X1283675D01*
G01X1290805Y673208D02*
X1291890Y674667D01*
X1292820Y675500D01*
X1294060Y675917D01*
X1295145Y675500D01*
X1295920Y674667D01*
X1296540Y673417D01*
X1296695Y671958D01*
X1296540Y670708D01*
X1295920Y669458D01*
X1294990Y668417D01*
X1293905Y668000D01*
X1292665Y668417D01*
X1291580Y669666D01*
X1290960Y671542D01*
X1290805Y673625D01*
X1291115Y676333D01*
X1291580Y677792D01*
X1292355Y679250D01*
X1293440Y680292D01*
X1294525Y680500D01*
X1295610Y680083D01*
X1296385Y679042D01*
G01X1250350Y780400D02*
Y792900D01*
X1248490Y790400D01*
G01Y780400D02*
X1252210D01*
G01X1262750Y792900D02*
X1261510Y792483D01*
X1260580Y791442D01*
X1259960Y790192D01*
X1259495Y788525D01*
X1259340Y786650D01*
X1259495Y784775D01*
X1259960Y783108D01*
X1260580Y781858D01*
X1261510Y780817D01*
X1262750Y780400D01*
X1263990Y780817D01*
X1264920Y781858D01*
X1265540Y783108D01*
X1266005Y784775D01*
X1266160Y786650D01*
X1266005Y788525D01*
X1265540Y790192D01*
X1264920Y791442D01*
X1263990Y792483D01*
X1262750Y792900D01*
G01X1275150Y779983D02*
X1274840Y780192D01*
Y780608D01*
X1275150Y780817D01*
X1275460Y780608D01*
Y780192D01*
X1275150Y779983D01*
G01X1287550Y792900D02*
X1286310Y792483D01*
X1285380Y791442D01*
X1284760Y790192D01*
X1284295Y788525D01*
X1284140Y786650D01*
X1284295Y784775D01*
X1284760Y783108D01*
X1285380Y781858D01*
X1286310Y780817D01*
X1287550Y780400D01*
X1288790Y780817D01*
X1289720Y781858D01*
X1290340Y783108D01*
X1290805Y784775D01*
X1290960Y786650D01*
X1290805Y788525D01*
X1290340Y790192D01*
X1289720Y791442D01*
X1288790Y792483D01*
X1287550Y792900D01*
G01X1250350Y752300D02*
Y764800D01*
X1248490Y762300D01*
G01Y752300D02*
X1252210D01*
G01X1262750Y764800D02*
X1261510Y764383D01*
X1260580Y763342D01*
X1259960Y762092D01*
X1259495Y760425D01*
X1259340Y758550D01*
X1259495Y756675D01*
X1259960Y755008D01*
X1260580Y753758D01*
X1261510Y752717D01*
X1262750Y752300D01*
X1263990Y752717D01*
X1264920Y753758D01*
X1265540Y755008D01*
X1266005Y756675D01*
X1266160Y758550D01*
X1266005Y760425D01*
X1265540Y762092D01*
X1264920Y763342D01*
X1263990Y764383D01*
X1262750Y764800D01*
G01X1275150Y751883D02*
X1274840Y752092D01*
Y752508D01*
X1275150Y752717D01*
X1275460Y752508D01*
Y752092D01*
X1275150Y751883D01*
G01X1287550Y764800D02*
X1286310Y764383D01*
X1285380Y763342D01*
X1284760Y762092D01*
X1284295Y760425D01*
X1284140Y758550D01*
X1284295Y756675D01*
X1284760Y755008D01*
X1285380Y753758D01*
X1286310Y752717D01*
X1287550Y752300D01*
X1288790Y752717D01*
X1289720Y753758D01*
X1290340Y755008D01*
X1290805Y756675D01*
X1290960Y758550D01*
X1290805Y760425D01*
X1290340Y762092D01*
X1289720Y763342D01*
X1288790Y764383D01*
X1287550Y764800D01*
G01X1247095Y839816D02*
X1248335Y838775D01*
X1249730Y838150D01*
X1250970D01*
X1252210Y838775D01*
X1253140Y839816D01*
X1253605Y841275D01*
X1253295Y842733D01*
X1252520Y843983D01*
X1251125Y844817D01*
X1249265Y845233D01*
X1248180Y846067D01*
X1247715Y847525D01*
X1248025Y848983D01*
X1248800Y850025D01*
X1249885Y850650D01*
X1250970D01*
X1252055Y850233D01*
X1252985Y849192D01*
G01X1260890Y850650D02*
X1264610D01*
G01X1262750D02*
Y838150D01*
G01X1260890D02*
X1264610D01*
G01X1272205Y850650D02*
X1278095D01*
X1272205Y838150D01*
X1278095D01*
G01X1290650D02*
X1284450D01*
Y850650D01*
X1290650D01*
G01X1288170Y844608D02*
X1284450D01*
G01X1256550Y808500D02*
X1257635Y808708D01*
X1258875Y809333D01*
X1259650Y810375D01*
X1259960Y811833D01*
X1259650Y813291D01*
X1258720Y814542D01*
X1257325Y815167D01*
X1255775D01*
X1254845Y815583D01*
X1254070Y816625D01*
X1253760Y818083D01*
X1254225Y819542D01*
X1255310Y820583D01*
X1256550Y821000D01*
X1257790Y820583D01*
X1258875Y819542D01*
X1259340Y818083D01*
X1259030Y816625D01*
X1258255Y815583D01*
X1257325Y815167D01*
X1255775D01*
X1254380Y814542D01*
X1253450Y813291D01*
X1253140Y811833D01*
X1253450Y810375D01*
X1254225Y809333D01*
X1255465Y808708D01*
X1256550Y808500D01*
G01X1268950Y808083D02*
X1268640Y808292D01*
Y808708D01*
X1268950Y808917D01*
X1269260Y808708D01*
Y808292D01*
X1268950Y808083D01*
G01X1281350Y821000D02*
X1280110Y820583D01*
X1279180Y819542D01*
X1278560Y818292D01*
X1278095Y816625D01*
X1277940Y814750D01*
X1278095Y812875D01*
X1278560Y811208D01*
X1279180Y809958D01*
X1280110Y808917D01*
X1281350Y808500D01*
X1282590Y808917D01*
X1283520Y809958D01*
X1284140Y811208D01*
X1284605Y812875D01*
X1284760Y814750D01*
X1284605Y816625D01*
X1284140Y818292D01*
X1283520Y819542D01*
X1282590Y820583D01*
X1281350Y821000D01*
G01X1198425Y866250D02*
X1202300Y878750D01*
X1206175Y866250D01*
G01X1204780Y870625D02*
X1199820D01*
G01X1211600Y878750D02*
Y866250D01*
X1217800D01*
G01X1224000Y878750D02*
Y866250D01*
X1230200D01*
G01X1248490Y878750D02*
Y869792D01*
X1249110Y867916D01*
X1250350Y866667D01*
X1251900Y866250D01*
X1253450Y866667D01*
X1254690Y867916D01*
X1255310Y869792D01*
Y878750D01*
G01X1260735Y866250D02*
Y878750D01*
X1267865Y866250D01*
Y878750D01*
G01X1274840D02*
X1278560D01*
G01X1276700D02*
Y866250D01*
G01X1274840D02*
X1278560D01*
G01X1289100Y878750D02*
Y866250D01*
G01X1285535Y878750D02*
X1292665D01*
G01X1298245Y867916D02*
X1299485Y866875D01*
X1300880Y866250D01*
X1302120D01*
X1303360Y866875D01*
X1304290Y867916D01*
X1304755Y869375D01*
X1304445Y870833D01*
X1303670Y872083D01*
X1302275Y872917D01*
X1300415Y873333D01*
X1299330Y874167D01*
X1298865Y875625D01*
X1299175Y877083D01*
X1299950Y878125D01*
X1301035Y878750D01*
X1302120D01*
X1303205Y878333D01*
X1304135Y877292D01*
G01X1322425Y866250D02*
X1326300Y878750D01*
X1330175Y866250D01*
G01X1328780Y870625D02*
X1323820D01*
G01X1335600Y866250D02*
Y878750D01*
X1339475D01*
X1340715Y878125D01*
X1341490Y877292D01*
X1341800Y875625D01*
X1341490Y873958D01*
X1340560Y872917D01*
X1339475Y872292D01*
X1335600D01*
G01X1339475D02*
X1341800Y866250D01*
G01X1354200D02*
X1348000D01*
Y878750D01*
X1354200D01*
G01X1351720Y872708D02*
X1348000D01*
G01X1374040Y878750D02*
X1377760D01*
G01X1375900D02*
Y866250D01*
G01X1374040D02*
X1377760D01*
G01X1384735D02*
Y878750D01*
X1391865Y866250D01*
Y878750D01*
G01X1409070Y866250D02*
Y878750D01*
X1413100Y868333D01*
X1417130Y878750D01*
Y866250D01*
G01X1423640Y878750D02*
X1427360D01*
G01X1425500D02*
Y866250D01*
G01X1423640D02*
X1427360D01*
G01X1434800Y878750D02*
Y866250D01*
X1441000D01*
G01X1447045Y867916D02*
X1448285Y866875D01*
X1449680Y866250D01*
X1450920D01*
X1452160Y866875D01*
X1453090Y867916D01*
X1453555Y869375D01*
X1453245Y870833D01*
X1452470Y872083D01*
X1451075Y872917D01*
X1449215Y873333D01*
X1448130Y874167D01*
X1447665Y875625D01*
X1447975Y877083D01*
X1448750Y878125D01*
X1449835Y878750D01*
X1450920D01*
X1452005Y878333D01*
X1452935Y877292D01*
G01X1367685Y106000D02*
Y118500D01*
X1374815Y106000D01*
Y118500D01*
G01X1383650Y106000D02*
X1382410Y106208D01*
X1381325Y107041D01*
X1380395Y108292D01*
X1379775Y109750D01*
X1379465Y111417D01*
Y113083D01*
X1379775Y114750D01*
X1380395Y116208D01*
X1381325Y117458D01*
X1382410Y118292D01*
X1383650Y118500D01*
X1384890Y118292D01*
X1385975Y117458D01*
X1386905Y116208D01*
X1387525Y114750D01*
X1387835Y113083D01*
Y111417D01*
X1387525Y109750D01*
X1386905Y108292D01*
X1385975Y107041D01*
X1384890Y106208D01*
X1383650Y106000D01*
G01X1392485D02*
Y118500D01*
X1399615Y106000D01*
Y118500D01*
G01X1406435Y110167D02*
X1410465D01*
G01X1417750Y106000D02*
Y118500D01*
X1421470D01*
X1422710Y117875D01*
X1423640Y116417D01*
X1423950Y114750D01*
X1423640Y113083D01*
X1422865Y111833D01*
X1421470Y111208D01*
X1417750D01*
G01X1430150Y118500D02*
Y106000D01*
X1436350D01*
G01X1441775D02*
X1445650Y118500D01*
X1449525Y106000D01*
G01X1448130Y110375D02*
X1443170D01*
G01X1458050Y118500D02*
Y106000D01*
G01X1454485Y118500D02*
X1461615D01*
G01X1473550Y106000D02*
X1467350D01*
Y118500D01*
X1473550D01*
G01X1471070Y112458D02*
X1467350D01*
G01X1479440Y106000D02*
Y118500D01*
X1482540D01*
X1483780Y117875D01*
X1484710Y117042D01*
X1485485Y115792D01*
X1486105Y114333D01*
X1486260Y112250D01*
X1486105Y110167D01*
X1485485Y108708D01*
X1484710Y107458D01*
X1483780Y106625D01*
X1482540Y106000D01*
X1479440D01*
G01X1363500Y856900D02*
Y98200D01*
G01X1367685Y190300D02*
Y202800D01*
X1374815Y190300D01*
Y202800D01*
G01X1383650Y190300D02*
X1382410Y190508D01*
X1381325Y191341D01*
X1380395Y192592D01*
X1379775Y194050D01*
X1379465Y195717D01*
Y197383D01*
X1379775Y199050D01*
X1380395Y200508D01*
X1381325Y201758D01*
X1382410Y202592D01*
X1383650Y202800D01*
X1384890Y202592D01*
X1385975Y201758D01*
X1386905Y200508D01*
X1387525Y199050D01*
X1387835Y197383D01*
Y195717D01*
X1387525Y194050D01*
X1386905Y192592D01*
X1385975Y191341D01*
X1384890Y190508D01*
X1383650Y190300D01*
G01X1392485D02*
Y202800D01*
X1399615Y190300D01*
Y202800D01*
G01X1406435Y194467D02*
X1410465D01*
G01X1417750Y190300D02*
Y202800D01*
X1421470D01*
X1422710Y202175D01*
X1423640Y200717D01*
X1423950Y199050D01*
X1423640Y197383D01*
X1422865Y196133D01*
X1421470Y195508D01*
X1417750D01*
G01X1430150Y202800D02*
Y190300D01*
X1436350D01*
G01X1441775D02*
X1445650Y202800D01*
X1449525Y190300D01*
G01X1448130Y194675D02*
X1443170D01*
G01X1458050Y202800D02*
Y190300D01*
G01X1454485Y202800D02*
X1461615D01*
G01X1473550Y190300D02*
X1467350D01*
Y202800D01*
X1473550D01*
G01X1471070Y196758D02*
X1467350D01*
G01X1479440Y190300D02*
Y202800D01*
X1482540D01*
X1483780Y202175D01*
X1484710Y201342D01*
X1485485Y200092D01*
X1486105Y198633D01*
X1486260Y196550D01*
X1486105Y194467D01*
X1485485Y193008D01*
X1484710Y191758D01*
X1483780Y190925D01*
X1482540Y190300D01*
X1479440D01*
G01X1367685Y246500D02*
Y259000D01*
X1374815Y246500D01*
Y259000D01*
G01X1383650Y246500D02*
X1382410Y246708D01*
X1381325Y247541D01*
X1380395Y248792D01*
X1379775Y250250D01*
X1379465Y251917D01*
Y253583D01*
X1379775Y255250D01*
X1380395Y256708D01*
X1381325Y257958D01*
X1382410Y258792D01*
X1383650Y259000D01*
X1384890Y258792D01*
X1385975Y257958D01*
X1386905Y256708D01*
X1387525Y255250D01*
X1387835Y253583D01*
Y251917D01*
X1387525Y250250D01*
X1386905Y248792D01*
X1385975Y247541D01*
X1384890Y246708D01*
X1383650Y246500D01*
G01X1392485D02*
Y259000D01*
X1399615Y246500D01*
Y259000D01*
G01X1406435Y250667D02*
X1410465D01*
G01X1417750Y246500D02*
Y259000D01*
X1421470D01*
X1422710Y258375D01*
X1423640Y256917D01*
X1423950Y255250D01*
X1423640Y253583D01*
X1422865Y252333D01*
X1421470Y251708D01*
X1417750D01*
G01X1430150Y259000D02*
Y246500D01*
X1436350D01*
G01X1441775D02*
X1445650Y259000D01*
X1449525Y246500D01*
G01X1448130Y250875D02*
X1443170D01*
G01X1458050Y259000D02*
Y246500D01*
G01X1454485Y259000D02*
X1461615D01*
G01X1473550Y246500D02*
X1467350D01*
Y259000D01*
X1473550D01*
G01X1471070Y252958D02*
X1467350D01*
G01X1479440Y246500D02*
Y259000D01*
X1482540D01*
X1483780Y258375D01*
X1484710Y257542D01*
X1485485Y256292D01*
X1486105Y254833D01*
X1486260Y252750D01*
X1486105Y250667D01*
X1485485Y249208D01*
X1484710Y247958D01*
X1483780Y247125D01*
X1482540Y246500D01*
X1479440D01*
G01X1367685Y218400D02*
Y230900D01*
X1374815Y218400D01*
Y230900D01*
G01X1383650Y218400D02*
X1382410Y218608D01*
X1381325Y219441D01*
X1380395Y220692D01*
X1379775Y222150D01*
X1379465Y223817D01*
Y225483D01*
X1379775Y227150D01*
X1380395Y228608D01*
X1381325Y229858D01*
X1382410Y230692D01*
X1383650Y230900D01*
X1384890Y230692D01*
X1385975Y229858D01*
X1386905Y228608D01*
X1387525Y227150D01*
X1387835Y225483D01*
Y223817D01*
X1387525Y222150D01*
X1386905Y220692D01*
X1385975Y219441D01*
X1384890Y218608D01*
X1383650Y218400D01*
G01X1392485D02*
Y230900D01*
X1399615Y218400D01*
Y230900D01*
G01X1406435Y222567D02*
X1410465D01*
G01X1417750Y218400D02*
Y230900D01*
X1421470D01*
X1422710Y230275D01*
X1423640Y228817D01*
X1423950Y227150D01*
X1423640Y225483D01*
X1422865Y224233D01*
X1421470Y223608D01*
X1417750D01*
G01X1430150Y230900D02*
Y218400D01*
X1436350D01*
G01X1441775D02*
X1445650Y230900D01*
X1449525Y218400D01*
G01X1448130Y222775D02*
X1443170D01*
G01X1458050Y230900D02*
Y218400D01*
G01X1454485Y230900D02*
X1461615D01*
G01X1473550Y218400D02*
X1467350D01*
Y230900D01*
X1473550D01*
G01X1471070Y224858D02*
X1467350D01*
G01X1479440Y218400D02*
Y230900D01*
X1482540D01*
X1483780Y230275D01*
X1484710Y229442D01*
X1485485Y228192D01*
X1486105Y226733D01*
X1486260Y224650D01*
X1486105Y222567D01*
X1485485Y221108D01*
X1484710Y219858D01*
X1483780Y219025D01*
X1482540Y218400D01*
X1479440D01*
G01X1367685Y330800D02*
Y343300D01*
X1374815Y330800D01*
Y343300D01*
G01X1383650Y330800D02*
X1382410Y331008D01*
X1381325Y331841D01*
X1380395Y333092D01*
X1379775Y334550D01*
X1379465Y336217D01*
Y337883D01*
X1379775Y339550D01*
X1380395Y341008D01*
X1381325Y342258D01*
X1382410Y343092D01*
X1383650Y343300D01*
X1384890Y343092D01*
X1385975Y342258D01*
X1386905Y341008D01*
X1387525Y339550D01*
X1387835Y337883D01*
Y336217D01*
X1387525Y334550D01*
X1386905Y333092D01*
X1385975Y331841D01*
X1384890Y331008D01*
X1383650Y330800D01*
G01X1392485D02*
Y343300D01*
X1399615Y330800D01*
Y343300D01*
G01X1406435Y334967D02*
X1410465D01*
G01X1417750Y330800D02*
Y343300D01*
X1421470D01*
X1422710Y342675D01*
X1423640Y341217D01*
X1423950Y339550D01*
X1423640Y337883D01*
X1422865Y336633D01*
X1421470Y336008D01*
X1417750D01*
G01X1430150Y343300D02*
Y330800D01*
X1436350D01*
G01X1441775D02*
X1445650Y343300D01*
X1449525Y330800D01*
G01X1448130Y335175D02*
X1443170D01*
G01X1458050Y343300D02*
Y330800D01*
G01X1454485Y343300D02*
X1461615D01*
G01X1473550Y330800D02*
X1467350D01*
Y343300D01*
X1473550D01*
G01X1471070Y337258D02*
X1467350D01*
G01X1479440Y330800D02*
Y343300D01*
X1482540D01*
X1483780Y342675D01*
X1484710Y341842D01*
X1485485Y340592D01*
X1486105Y339133D01*
X1486260Y337050D01*
X1486105Y334967D01*
X1485485Y333508D01*
X1484710Y332258D01*
X1483780Y331425D01*
X1482540Y330800D01*
X1479440D01*
G01X1367685Y302700D02*
Y315200D01*
X1374815Y302700D01*
Y315200D01*
G01X1383650Y302700D02*
X1382410Y302908D01*
X1381325Y303741D01*
X1380395Y304992D01*
X1379775Y306450D01*
X1379465Y308117D01*
Y309783D01*
X1379775Y311450D01*
X1380395Y312908D01*
X1381325Y314158D01*
X1382410Y314992D01*
X1383650Y315200D01*
X1384890Y314992D01*
X1385975Y314158D01*
X1386905Y312908D01*
X1387525Y311450D01*
X1387835Y309783D01*
Y308117D01*
X1387525Y306450D01*
X1386905Y304992D01*
X1385975Y303741D01*
X1384890Y302908D01*
X1383650Y302700D01*
G01X1392485D02*
Y315200D01*
X1399615Y302700D01*
Y315200D01*
G01X1406435Y306867D02*
X1410465D01*
G01X1417750Y302700D02*
Y315200D01*
X1421470D01*
X1422710Y314575D01*
X1423640Y313117D01*
X1423950Y311450D01*
X1423640Y309783D01*
X1422865Y308533D01*
X1421470Y307908D01*
X1417750D01*
G01X1430150Y315200D02*
Y302700D01*
X1436350D01*
G01X1441775D02*
X1445650Y315200D01*
X1449525Y302700D01*
G01X1448130Y307075D02*
X1443170D01*
G01X1458050Y315200D02*
Y302700D01*
G01X1454485Y315200D02*
X1461615D01*
G01X1473550Y302700D02*
X1467350D01*
Y315200D01*
X1473550D01*
G01X1471070Y309158D02*
X1467350D01*
G01X1479440Y302700D02*
Y315200D01*
X1482540D01*
X1483780Y314575D01*
X1484710Y313742D01*
X1485485Y312492D01*
X1486105Y311033D01*
X1486260Y308950D01*
X1486105Y306867D01*
X1485485Y305408D01*
X1484710Y304158D01*
X1483780Y303325D01*
X1482540Y302700D01*
X1479440D01*
G01X1367685Y274600D02*
Y287100D01*
X1374815Y274600D01*
Y287100D01*
G01X1383650Y274600D02*
X1382410Y274808D01*
X1381325Y275641D01*
X1380395Y276892D01*
X1379775Y278350D01*
X1379465Y280017D01*
Y281683D01*
X1379775Y283350D01*
X1380395Y284808D01*
X1381325Y286058D01*
X1382410Y286892D01*
X1383650Y287100D01*
X1384890Y286892D01*
X1385975Y286058D01*
X1386905Y284808D01*
X1387525Y283350D01*
X1387835Y281683D01*
Y280017D01*
X1387525Y278350D01*
X1386905Y276892D01*
X1385975Y275641D01*
X1384890Y274808D01*
X1383650Y274600D01*
G01X1392485D02*
Y287100D01*
X1399615Y274600D01*
Y287100D01*
G01X1406435Y278767D02*
X1410465D01*
G01X1417750Y274600D02*
Y287100D01*
X1421470D01*
X1422710Y286475D01*
X1423640Y285017D01*
X1423950Y283350D01*
X1423640Y281683D01*
X1422865Y280433D01*
X1421470Y279808D01*
X1417750D01*
G01X1430150Y287100D02*
Y274600D01*
X1436350D01*
G01X1441775D02*
X1445650Y287100D01*
X1449525Y274600D01*
G01X1448130Y278975D02*
X1443170D01*
G01X1458050Y287100D02*
Y274600D01*
G01X1454485Y287100D02*
X1461615D01*
G01X1473550Y274600D02*
X1467350D01*
Y287100D01*
X1473550D01*
G01X1471070Y281058D02*
X1467350D01*
G01X1479440Y274600D02*
Y287100D01*
X1482540D01*
X1483780Y286475D01*
X1484710Y285642D01*
X1485485Y284392D01*
X1486105Y282933D01*
X1486260Y280850D01*
X1486105Y278767D01*
X1485485Y277308D01*
X1484710Y276058D01*
X1483780Y275225D01*
X1482540Y274600D01*
X1479440D01*
G01X1367685Y387000D02*
Y399500D01*
X1374815Y387000D01*
Y399500D01*
G01X1383650Y387000D02*
X1382410Y387208D01*
X1381325Y388041D01*
X1380395Y389292D01*
X1379775Y390750D01*
X1379465Y392417D01*
Y394083D01*
X1379775Y395750D01*
X1380395Y397208D01*
X1381325Y398458D01*
X1382410Y399292D01*
X1383650Y399500D01*
X1384890Y399292D01*
X1385975Y398458D01*
X1386905Y397208D01*
X1387525Y395750D01*
X1387835Y394083D01*
Y392417D01*
X1387525Y390750D01*
X1386905Y389292D01*
X1385975Y388041D01*
X1384890Y387208D01*
X1383650Y387000D01*
G01X1392485D02*
Y399500D01*
X1399615Y387000D01*
Y399500D01*
G01X1406435Y391167D02*
X1410465D01*
G01X1417750Y387000D02*
Y399500D01*
X1421470D01*
X1422710Y398875D01*
X1423640Y397417D01*
X1423950Y395750D01*
X1423640Y394083D01*
X1422865Y392833D01*
X1421470Y392208D01*
X1417750D01*
G01X1430150Y399500D02*
Y387000D01*
X1436350D01*
G01X1441775D02*
X1445650Y399500D01*
X1449525Y387000D01*
G01X1448130Y391375D02*
X1443170D01*
G01X1458050Y399500D02*
Y387000D01*
G01X1454485Y399500D02*
X1461615D01*
G01X1473550Y387000D02*
X1467350D01*
Y399500D01*
X1473550D01*
G01X1471070Y393458D02*
X1467350D01*
G01X1479440Y387000D02*
Y399500D01*
X1482540D01*
X1483780Y398875D01*
X1484710Y398042D01*
X1485485Y396792D01*
X1486105Y395333D01*
X1486260Y393250D01*
X1486105Y391167D01*
X1485485Y389708D01*
X1484710Y388458D01*
X1483780Y387625D01*
X1482540Y387000D01*
X1479440D01*
G01X1367685Y358900D02*
Y371400D01*
X1374815Y358900D01*
Y371400D01*
G01X1383650Y358900D02*
X1382410Y359108D01*
X1381325Y359941D01*
X1380395Y361192D01*
X1379775Y362650D01*
X1379465Y364317D01*
Y365983D01*
X1379775Y367650D01*
X1380395Y369108D01*
X1381325Y370358D01*
X1382410Y371192D01*
X1383650Y371400D01*
X1384890Y371192D01*
X1385975Y370358D01*
X1386905Y369108D01*
X1387525Y367650D01*
X1387835Y365983D01*
Y364317D01*
X1387525Y362650D01*
X1386905Y361192D01*
X1385975Y359941D01*
X1384890Y359108D01*
X1383650Y358900D01*
G01X1392485D02*
Y371400D01*
X1399615Y358900D01*
Y371400D01*
G01X1406435Y363067D02*
X1410465D01*
G01X1417750Y358900D02*
Y371400D01*
X1421470D01*
X1422710Y370775D01*
X1423640Y369317D01*
X1423950Y367650D01*
X1423640Y365983D01*
X1422865Y364733D01*
X1421470Y364108D01*
X1417750D01*
G01X1430150Y371400D02*
Y358900D01*
X1436350D01*
G01X1441775D02*
X1445650Y371400D01*
X1449525Y358900D01*
G01X1448130Y363275D02*
X1443170D01*
G01X1458050Y371400D02*
Y358900D01*
G01X1454485Y371400D02*
X1461615D01*
G01X1473550Y358900D02*
X1467350D01*
Y371400D01*
X1473550D01*
G01X1471070Y365358D02*
X1467350D01*
G01X1479440Y358900D02*
Y371400D01*
X1482540D01*
X1483780Y370775D01*
X1484710Y369942D01*
X1485485Y368692D01*
X1486105Y367233D01*
X1486260Y365150D01*
X1486105Y363067D01*
X1485485Y361608D01*
X1484710Y360358D01*
X1483780Y359525D01*
X1482540Y358900D01*
X1479440D01*
G01X1392950Y134100D02*
Y146600D01*
X1396670D01*
X1397910Y145975D01*
X1398840Y144517D01*
X1399150Y142850D01*
X1398840Y141183D01*
X1398065Y139933D01*
X1396670Y139308D01*
X1392950D01*
G01X1405350Y146600D02*
Y134100D01*
X1411550D01*
G01X1416975D02*
X1420850Y146600D01*
X1424725Y134100D01*
G01X1423330Y138475D02*
X1418370D01*
G01X1433250Y146600D02*
Y134100D01*
G01X1429685Y146600D02*
X1436815D01*
G01X1448750Y134100D02*
X1442550D01*
Y146600D01*
X1448750D01*
G01X1446270Y140558D02*
X1442550D01*
G01X1454640Y134100D02*
Y146600D01*
X1457740D01*
X1458980Y145975D01*
X1459910Y145142D01*
X1460685Y143892D01*
X1461305Y142433D01*
X1461460Y140350D01*
X1461305Y138267D01*
X1460685Y136808D01*
X1459910Y135558D01*
X1458980Y134725D01*
X1457740Y134100D01*
X1454640D01*
G01X1392950Y162200D02*
Y174700D01*
X1396670D01*
X1397910Y174075D01*
X1398840Y172617D01*
X1399150Y170950D01*
X1398840Y169283D01*
X1398065Y168033D01*
X1396670Y167408D01*
X1392950D01*
G01X1405350Y174700D02*
Y162200D01*
X1411550D01*
G01X1416975D02*
X1420850Y174700D01*
X1424725Y162200D01*
G01X1423330Y166575D02*
X1418370D01*
G01X1433250Y174700D02*
Y162200D01*
G01X1429685Y174700D02*
X1436815D01*
G01X1448750Y162200D02*
X1442550D01*
Y174700D01*
X1448750D01*
G01X1446270Y168658D02*
X1442550D01*
G01X1454640Y162200D02*
Y174700D01*
X1457740D01*
X1458980Y174075D01*
X1459910Y173242D01*
X1460685Y171992D01*
X1461305Y170533D01*
X1461460Y168450D01*
X1461305Y166367D01*
X1460685Y164908D01*
X1459910Y163658D01*
X1458980Y162825D01*
X1457740Y162200D01*
X1454640D01*
G01X1392950Y443200D02*
Y455700D01*
X1396670D01*
X1397910Y455075D01*
X1398840Y453617D01*
X1399150Y451950D01*
X1398840Y450283D01*
X1398065Y449033D01*
X1396670Y448408D01*
X1392950D01*
G01X1405350Y455700D02*
Y443200D01*
X1411550D01*
G01X1416975D02*
X1420850Y455700D01*
X1424725Y443200D01*
G01X1423330Y447575D02*
X1418370D01*
G01X1433250Y455700D02*
Y443200D01*
G01X1429685Y455700D02*
X1436815D01*
G01X1448750Y443200D02*
X1442550D01*
Y455700D01*
X1448750D01*
G01X1446270Y449658D02*
X1442550D01*
G01X1454640Y443200D02*
Y455700D01*
X1457740D01*
X1458980Y455075D01*
X1459910Y454242D01*
X1460685Y452992D01*
X1461305Y451533D01*
X1461460Y449450D01*
X1461305Y447367D01*
X1460685Y445908D01*
X1459910Y444658D01*
X1458980Y443825D01*
X1457740Y443200D01*
X1454640D01*
G01X1392950Y415100D02*
Y427600D01*
X1396670D01*
X1397910Y426975D01*
X1398840Y425517D01*
X1399150Y423850D01*
X1398840Y422183D01*
X1398065Y420933D01*
X1396670Y420308D01*
X1392950D01*
G01X1405350Y427600D02*
Y415100D01*
X1411550D01*
G01X1416975D02*
X1420850Y427600D01*
X1424725Y415100D01*
G01X1423330Y419475D02*
X1418370D01*
G01X1433250Y427600D02*
Y415100D01*
G01X1429685Y427600D02*
X1436815D01*
G01X1448750Y415100D02*
X1442550D01*
Y427600D01*
X1448750D01*
G01X1446270Y421558D02*
X1442550D01*
G01X1454640Y415100D02*
Y427600D01*
X1457740D01*
X1458980Y426975D01*
X1459910Y426142D01*
X1460685Y424892D01*
X1461305Y423433D01*
X1461460Y421350D01*
X1461305Y419267D01*
X1460685Y417808D01*
X1459910Y416558D01*
X1458980Y415725D01*
X1457740Y415100D01*
X1454640D01*
G01X1392950Y527500D02*
Y540000D01*
X1396670D01*
X1397910Y539375D01*
X1398840Y537917D01*
X1399150Y536250D01*
X1398840Y534583D01*
X1398065Y533333D01*
X1396670Y532708D01*
X1392950D01*
G01X1405350Y540000D02*
Y527500D01*
X1411550D01*
G01X1416975D02*
X1420850Y540000D01*
X1424725Y527500D01*
G01X1423330Y531875D02*
X1418370D01*
G01X1433250Y540000D02*
Y527500D01*
G01X1429685Y540000D02*
X1436815D01*
G01X1448750Y527500D02*
X1442550D01*
Y540000D01*
X1448750D01*
G01X1446270Y533958D02*
X1442550D01*
G01X1454640Y527500D02*
Y540000D01*
X1457740D01*
X1458980Y539375D01*
X1459910Y538542D01*
X1460685Y537292D01*
X1461305Y535833D01*
X1461460Y533750D01*
X1461305Y531667D01*
X1460685Y530208D01*
X1459910Y528958D01*
X1458980Y528125D01*
X1457740Y527500D01*
X1454640D01*
G01X1392950Y499400D02*
Y511900D01*
X1396670D01*
X1397910Y511275D01*
X1398840Y509817D01*
X1399150Y508150D01*
X1398840Y506483D01*
X1398065Y505233D01*
X1396670Y504608D01*
X1392950D01*
G01X1405350Y511900D02*
Y499400D01*
X1411550D01*
G01X1416975D02*
X1420850Y511900D01*
X1424725Y499400D01*
G01X1423330Y503775D02*
X1418370D01*
G01X1433250Y511900D02*
Y499400D01*
G01X1429685Y511900D02*
X1436815D01*
G01X1448750Y499400D02*
X1442550D01*
Y511900D01*
X1448750D01*
G01X1446270Y505858D02*
X1442550D01*
G01X1454640Y499400D02*
Y511900D01*
X1457740D01*
X1458980Y511275D01*
X1459910Y510442D01*
X1460685Y509192D01*
X1461305Y507733D01*
X1461460Y505650D01*
X1461305Y503567D01*
X1460685Y502108D01*
X1459910Y500858D01*
X1458980Y500025D01*
X1457740Y499400D01*
X1454640D01*
G01X1392950Y471300D02*
Y483800D01*
X1396670D01*
X1397910Y483175D01*
X1398840Y481717D01*
X1399150Y480050D01*
X1398840Y478383D01*
X1398065Y477133D01*
X1396670Y476508D01*
X1392950D01*
G01X1405350Y483800D02*
Y471300D01*
X1411550D01*
G01X1416975D02*
X1420850Y483800D01*
X1424725Y471300D01*
G01X1423330Y475675D02*
X1418370D01*
G01X1433250Y483800D02*
Y471300D01*
G01X1429685Y483800D02*
X1436815D01*
G01X1448750Y471300D02*
X1442550D01*
Y483800D01*
X1448750D01*
G01X1446270Y477758D02*
X1442550D01*
G01X1454640Y471300D02*
Y483800D01*
X1457740D01*
X1458980Y483175D01*
X1459910Y482342D01*
X1460685Y481092D01*
X1461305Y479633D01*
X1461460Y477550D01*
X1461305Y475467D01*
X1460685Y474008D01*
X1459910Y472758D01*
X1458980Y471925D01*
X1457740Y471300D01*
X1454640D01*
G01X1392950Y583700D02*
Y596200D01*
X1396670D01*
X1397910Y595575D01*
X1398840Y594117D01*
X1399150Y592450D01*
X1398840Y590783D01*
X1398065Y589533D01*
X1396670Y588908D01*
X1392950D01*
G01X1405350Y596200D02*
Y583700D01*
X1411550D01*
G01X1416975D02*
X1420850Y596200D01*
X1424725Y583700D01*
G01X1423330Y588075D02*
X1418370D01*
G01X1433250Y596200D02*
Y583700D01*
G01X1429685Y596200D02*
X1436815D01*
G01X1448750Y583700D02*
X1442550D01*
Y596200D01*
X1448750D01*
G01X1446270Y590158D02*
X1442550D01*
G01X1454640Y583700D02*
Y596200D01*
X1457740D01*
X1458980Y595575D01*
X1459910Y594742D01*
X1460685Y593492D01*
X1461305Y592033D01*
X1461460Y589950D01*
X1461305Y587867D01*
X1460685Y586408D01*
X1459910Y585158D01*
X1458980Y584325D01*
X1457740Y583700D01*
X1454640D01*
G01X1392950Y555600D02*
Y568100D01*
X1396670D01*
X1397910Y567475D01*
X1398840Y566017D01*
X1399150Y564350D01*
X1398840Y562683D01*
X1398065Y561433D01*
X1396670Y560808D01*
X1392950D01*
G01X1405350Y568100D02*
Y555600D01*
X1411550D01*
G01X1416975D02*
X1420850Y568100D01*
X1424725Y555600D01*
G01X1423330Y559975D02*
X1418370D01*
G01X1433250Y568100D02*
Y555600D01*
G01X1429685Y568100D02*
X1436815D01*
G01X1448750Y555600D02*
X1442550D01*
Y568100D01*
X1448750D01*
G01X1446270Y562058D02*
X1442550D01*
G01X1454640Y555600D02*
Y568100D01*
X1457740D01*
X1458980Y567475D01*
X1459910Y566642D01*
X1460685Y565392D01*
X1461305Y563933D01*
X1461460Y561850D01*
X1461305Y559767D01*
X1460685Y558308D01*
X1459910Y557058D01*
X1458980Y556225D01*
X1457740Y555600D01*
X1454640D01*
G01X1392950Y639900D02*
Y652400D01*
X1396670D01*
X1397910Y651775D01*
X1398840Y650317D01*
X1399150Y648650D01*
X1398840Y646983D01*
X1398065Y645733D01*
X1396670Y645108D01*
X1392950D01*
G01X1405350Y652400D02*
Y639900D01*
X1411550D01*
G01X1416975D02*
X1420850Y652400D01*
X1424725Y639900D01*
G01X1423330Y644275D02*
X1418370D01*
G01X1433250Y652400D02*
Y639900D01*
G01X1429685Y652400D02*
X1436815D01*
G01X1448750Y639900D02*
X1442550D01*
Y652400D01*
X1448750D01*
G01X1446270Y646358D02*
X1442550D01*
G01X1454640Y639900D02*
Y652400D01*
X1457740D01*
X1458980Y651775D01*
X1459910Y650942D01*
X1460685Y649692D01*
X1461305Y648233D01*
X1461460Y646150D01*
X1461305Y644067D01*
X1460685Y642608D01*
X1459910Y641358D01*
X1458980Y640525D01*
X1457740Y639900D01*
X1454640D01*
G01X1392950Y611800D02*
Y624300D01*
X1396670D01*
X1397910Y623675D01*
X1398840Y622217D01*
X1399150Y620550D01*
X1398840Y618883D01*
X1398065Y617633D01*
X1396670Y617008D01*
X1392950D01*
G01X1405350Y624300D02*
Y611800D01*
X1411550D01*
G01X1416975D02*
X1420850Y624300D01*
X1424725Y611800D01*
G01X1423330Y616175D02*
X1418370D01*
G01X1433250Y624300D02*
Y611800D01*
G01X1429685Y624300D02*
X1436815D01*
G01X1448750Y611800D02*
X1442550D01*
Y624300D01*
X1448750D01*
G01X1446270Y618258D02*
X1442550D01*
G01X1454640Y611800D02*
Y624300D01*
X1457740D01*
X1458980Y623675D01*
X1459910Y622842D01*
X1460685Y621592D01*
X1461305Y620133D01*
X1461460Y618050D01*
X1461305Y615967D01*
X1460685Y614508D01*
X1459910Y613258D01*
X1458980Y612425D01*
X1457740Y611800D01*
X1454640D01*
G01X1392950Y724200D02*
Y736700D01*
X1396670D01*
X1397910Y736075D01*
X1398840Y734617D01*
X1399150Y732950D01*
X1398840Y731283D01*
X1398065Y730033D01*
X1396670Y729408D01*
X1392950D01*
G01X1405350Y736700D02*
Y724200D01*
X1411550D01*
G01X1416975D02*
X1420850Y736700D01*
X1424725Y724200D01*
G01X1423330Y728575D02*
X1418370D01*
G01X1433250Y736700D02*
Y724200D01*
G01X1429685Y736700D02*
X1436815D01*
G01X1448750Y724200D02*
X1442550D01*
Y736700D01*
X1448750D01*
G01X1446270Y730658D02*
X1442550D01*
G01X1454640Y724200D02*
Y736700D01*
X1457740D01*
X1458980Y736075D01*
X1459910Y735242D01*
X1460685Y733992D01*
X1461305Y732533D01*
X1461460Y730450D01*
X1461305Y728367D01*
X1460685Y726908D01*
X1459910Y725658D01*
X1458980Y724825D01*
X1457740Y724200D01*
X1454640D01*
G01X1392950Y696100D02*
Y708600D01*
X1396670D01*
X1397910Y707975D01*
X1398840Y706517D01*
X1399150Y704850D01*
X1398840Y703183D01*
X1398065Y701933D01*
X1396670Y701308D01*
X1392950D01*
G01X1405350Y708600D02*
Y696100D01*
X1411550D01*
G01X1416975D02*
X1420850Y708600D01*
X1424725Y696100D01*
G01X1423330Y700475D02*
X1418370D01*
G01X1433250Y708600D02*
Y696100D01*
G01X1429685Y708600D02*
X1436815D01*
G01X1448750Y696100D02*
X1442550D01*
Y708600D01*
X1448750D01*
G01X1446270Y702558D02*
X1442550D01*
G01X1454640Y696100D02*
Y708600D01*
X1457740D01*
X1458980Y707975D01*
X1459910Y707142D01*
X1460685Y705892D01*
X1461305Y704433D01*
X1461460Y702350D01*
X1461305Y700267D01*
X1460685Y698808D01*
X1459910Y697558D01*
X1458980Y696725D01*
X1457740Y696100D01*
X1454640D01*
G01X1392950Y668000D02*
Y680500D01*
X1396670D01*
X1397910Y679875D01*
X1398840Y678417D01*
X1399150Y676750D01*
X1398840Y675083D01*
X1398065Y673833D01*
X1396670Y673208D01*
X1392950D01*
G01X1405350Y680500D02*
Y668000D01*
X1411550D01*
G01X1416975D02*
X1420850Y680500D01*
X1424725Y668000D01*
G01X1423330Y672375D02*
X1418370D01*
G01X1433250Y680500D02*
Y668000D01*
G01X1429685Y680500D02*
X1436815D01*
G01X1448750Y668000D02*
X1442550D01*
Y680500D01*
X1448750D01*
G01X1446270Y674458D02*
X1442550D01*
G01X1454640Y668000D02*
Y680500D01*
X1457740D01*
X1458980Y679875D01*
X1459910Y679042D01*
X1460685Y677792D01*
X1461305Y676333D01*
X1461460Y674250D01*
X1461305Y672167D01*
X1460685Y670708D01*
X1459910Y669458D01*
X1458980Y668625D01*
X1457740Y668000D01*
X1454640D01*
G01X1392950Y780400D02*
Y792900D01*
X1396670D01*
X1397910Y792275D01*
X1398840Y790817D01*
X1399150Y789150D01*
X1398840Y787483D01*
X1398065Y786233D01*
X1396670Y785608D01*
X1392950D01*
G01X1405350Y792900D02*
Y780400D01*
X1411550D01*
G01X1416975D02*
X1420850Y792900D01*
X1424725Y780400D01*
G01X1423330Y784775D02*
X1418370D01*
G01X1433250Y792900D02*
Y780400D01*
G01X1429685Y792900D02*
X1436815D01*
G01X1448750Y780400D02*
X1442550D01*
Y792900D01*
X1448750D01*
G01X1446270Y786858D02*
X1442550D01*
G01X1454640Y780400D02*
Y792900D01*
X1457740D01*
X1458980Y792275D01*
X1459910Y791442D01*
X1460685Y790192D01*
X1461305Y788733D01*
X1461460Y786650D01*
X1461305Y784567D01*
X1460685Y783108D01*
X1459910Y781858D01*
X1458980Y781025D01*
X1457740Y780400D01*
X1454640D01*
G01X1392950Y752300D02*
Y764800D01*
X1396670D01*
X1397910Y764175D01*
X1398840Y762717D01*
X1399150Y761050D01*
X1398840Y759383D01*
X1398065Y758133D01*
X1396670Y757508D01*
X1392950D01*
G01X1405350Y764800D02*
Y752300D01*
X1411550D01*
G01X1416975D02*
X1420850Y764800D01*
X1424725Y752300D01*
G01X1423330Y756675D02*
X1418370D01*
G01X1433250Y764800D02*
Y752300D01*
G01X1429685Y764800D02*
X1436815D01*
G01X1448750Y752300D02*
X1442550D01*
Y764800D01*
X1448750D01*
G01X1446270Y758758D02*
X1442550D01*
G01X1454640Y752300D02*
Y764800D01*
X1457740D01*
X1458980Y764175D01*
X1459910Y763342D01*
X1460685Y762092D01*
X1461305Y760633D01*
X1461460Y758550D01*
X1461305Y756467D01*
X1460685Y755008D01*
X1459910Y753758D01*
X1458980Y752925D01*
X1457740Y752300D01*
X1454640D01*
G01X1392950Y838150D02*
Y850650D01*
X1396670D01*
X1397910Y850025D01*
X1398840Y848567D01*
X1399150Y846900D01*
X1398840Y845233D01*
X1398065Y843983D01*
X1396670Y843358D01*
X1392950D01*
G01X1405350Y850650D02*
Y838150D01*
X1411550D01*
G01X1416975D02*
X1420850Y850650D01*
X1424725Y838150D01*
G01X1423330Y842525D02*
X1418370D01*
G01X1433250Y850650D02*
Y838150D01*
G01X1429685Y850650D02*
X1436815D01*
G01X1448750Y838150D02*
X1442550D01*
Y850650D01*
X1448750D01*
G01X1446270Y844608D02*
X1442550D01*
G01X1454640Y838150D02*
Y850650D01*
X1457740D01*
X1458980Y850025D01*
X1459910Y849192D01*
X1460685Y847942D01*
X1461305Y846483D01*
X1461460Y844400D01*
X1461305Y842317D01*
X1460685Y840858D01*
X1459910Y839608D01*
X1458980Y838775D01*
X1457740Y838150D01*
X1454640D01*
G01X1392950Y808500D02*
Y821000D01*
X1396670D01*
X1397910Y820375D01*
X1398840Y818917D01*
X1399150Y817250D01*
X1398840Y815583D01*
X1398065Y814333D01*
X1396670Y813708D01*
X1392950D01*
G01X1405350Y821000D02*
Y808500D01*
X1411550D01*
G01X1416975D02*
X1420850Y821000D01*
X1424725Y808500D01*
G01X1423330Y812875D02*
X1418370D01*
G01X1433250Y821000D02*
Y808500D01*
G01X1429685Y821000D02*
X1436815D01*
G01X1448750Y808500D02*
X1442550D01*
Y821000D01*
X1448750D01*
G01X1446270Y814958D02*
X1442550D01*
G01X1454640Y808500D02*
Y821000D01*
X1457740D01*
X1458980Y820375D01*
X1459910Y819542D01*
X1460685Y818292D01*
X1461305Y816833D01*
X1461460Y814750D01*
X1461305Y812667D01*
X1460685Y811208D01*
X1459910Y809958D01*
X1458980Y809125D01*
X1457740Y808500D01*
X1454640D01*
G01X1490600Y856900D02*
Y98200D01*
G01X1523150Y527500D02*
Y540000D01*
X1521290Y537500D01*
G01Y527500D02*
X1525010D01*
G01X1535550D02*
Y540000D01*
X1533690Y537500D01*
G01Y527500D02*
X1537410D01*
G01X1514315Y641358D02*
X1515400Y640317D01*
X1516640Y639900D01*
X1517880Y640317D01*
X1518965Y641566D01*
X1519740Y643442D01*
X1520050Y645317D01*
Y647608D01*
X1519740Y649483D01*
X1518965Y651150D01*
X1518035Y651983D01*
X1516950Y652400D01*
X1515710Y651983D01*
X1514780Y651150D01*
X1514160Y649900D01*
X1513850Y648233D01*
X1514160Y646775D01*
X1514935Y645317D01*
X1515865Y644483D01*
X1516950Y644275D01*
X1518190Y644691D01*
X1519120Y645733D01*
X1520050Y647608D01*
G01X1529350Y652400D02*
X1528110Y651983D01*
X1527180Y650942D01*
X1526560Y649692D01*
X1526095Y648025D01*
X1525940Y646150D01*
X1526095Y644275D01*
X1526560Y642608D01*
X1527180Y641358D01*
X1528110Y640317D01*
X1529350Y639900D01*
X1530590Y640317D01*
X1531520Y641358D01*
X1532140Y642608D01*
X1532605Y644275D01*
X1532760Y646150D01*
X1532605Y648025D01*
X1532140Y649692D01*
X1531520Y650942D01*
X1530590Y651983D01*
X1529350Y652400D01*
G01X1541750Y639900D02*
X1542835Y640108D01*
X1544075Y640733D01*
X1544850Y641775D01*
X1545160Y643233D01*
X1544850Y644691D01*
X1543920Y645942D01*
X1542525Y646567D01*
X1540975D01*
X1540045Y646983D01*
X1539270Y648025D01*
X1538960Y649483D01*
X1539425Y650942D01*
X1540510Y651983D01*
X1541750Y652400D01*
X1542990Y651983D01*
X1544075Y650942D01*
X1544540Y649483D01*
X1544230Y648025D01*
X1543455Y646983D01*
X1542525Y646567D01*
X1540975D01*
X1539580Y645942D01*
X1538650Y644691D01*
X1538340Y643233D01*
X1538650Y641775D01*
X1539425Y640733D01*
X1540665Y640108D01*
X1541750Y639900D01*
G01X1523150Y611800D02*
Y624300D01*
X1521290Y621800D01*
G01Y611800D02*
X1525010D01*
G01X1532605Y622217D02*
X1533535Y623466D01*
X1534620Y624092D01*
X1535860Y624300D01*
X1537410Y623883D01*
X1538495Y622842D01*
X1538805Y621592D01*
X1538650Y620341D01*
X1538030Y619300D01*
X1534930Y617217D01*
X1533535Y615758D01*
X1532605Y613675D01*
X1532295Y611800D01*
X1538805D01*
G01X1523150Y724200D02*
X1524235Y724408D01*
X1525475Y725033D01*
X1526250Y726075D01*
X1526560Y727533D01*
X1526250Y728991D01*
X1525320Y730242D01*
X1523925Y730867D01*
X1522375D01*
X1521445Y731283D01*
X1520670Y732325D01*
X1520360Y733783D01*
X1520825Y735242D01*
X1521910Y736283D01*
X1523150Y736700D01*
X1524390Y736283D01*
X1525475Y735242D01*
X1525940Y733783D01*
X1525630Y732325D01*
X1524855Y731283D01*
X1523925Y730867D01*
X1522375D01*
X1520980Y730242D01*
X1520050Y728991D01*
X1519740Y727533D01*
X1520050Y726075D01*
X1520825Y725033D01*
X1522065Y724408D01*
X1523150Y724200D01*
G01X1532915Y725658D02*
X1534000Y724617D01*
X1535240Y724200D01*
X1536480Y724617D01*
X1537565Y725866D01*
X1538340Y727742D01*
X1538650Y729617D01*
Y731908D01*
X1538340Y733783D01*
X1537565Y735450D01*
X1536635Y736283D01*
X1535550Y736700D01*
X1534310Y736283D01*
X1533380Y735450D01*
X1532760Y734200D01*
X1532450Y732533D01*
X1532760Y731075D01*
X1533535Y729617D01*
X1534465Y728783D01*
X1535550Y728575D01*
X1536790Y728991D01*
X1537720Y730033D01*
X1538650Y731908D01*
G01X1514005Y706517D02*
X1514935Y707766D01*
X1516020Y708392D01*
X1517260Y708600D01*
X1518810Y708183D01*
X1519895Y707142D01*
X1520205Y705892D01*
X1520050Y704641D01*
X1519430Y703600D01*
X1516330Y701517D01*
X1514935Y700058D01*
X1514005Y697975D01*
X1513695Y696100D01*
X1520205D01*
G01X1529350Y708600D02*
X1528110Y708183D01*
X1527180Y707142D01*
X1526560Y705892D01*
X1526095Y704225D01*
X1525940Y702350D01*
X1526095Y700475D01*
X1526560Y698808D01*
X1527180Y697558D01*
X1528110Y696517D01*
X1529350Y696100D01*
X1530590Y696517D01*
X1531520Y697558D01*
X1532140Y698808D01*
X1532605Y700475D01*
X1532760Y702350D01*
X1532605Y704225D01*
X1532140Y705892D01*
X1531520Y707142D01*
X1530590Y708183D01*
X1529350Y708600D01*
G01X1541750D02*
X1540510Y708183D01*
X1539580Y707142D01*
X1538960Y705892D01*
X1538495Y704225D01*
X1538340Y702350D01*
X1538495Y700475D01*
X1538960Y698808D01*
X1539580Y697558D01*
X1540510Y696517D01*
X1541750Y696100D01*
X1542990Y696517D01*
X1543920Y697558D01*
X1544540Y698808D01*
X1545005Y700475D01*
X1545160Y702350D01*
X1545005Y704225D01*
X1544540Y705892D01*
X1543920Y707142D01*
X1542990Y708183D01*
X1541750Y708600D01*
G01X1522840Y668000D02*
X1523150Y670708D01*
X1523615Y673000D01*
X1524235Y675083D01*
X1525010Y677375D01*
X1526250Y680500D01*
X1520050D01*
G01X1532605Y678417D02*
X1533535Y679666D01*
X1534620Y680292D01*
X1535860Y680500D01*
X1537410Y680083D01*
X1538495Y679042D01*
X1538805Y677792D01*
X1538650Y676541D01*
X1538030Y675500D01*
X1534930Y673417D01*
X1533535Y671958D01*
X1532605Y669875D01*
X1532295Y668000D01*
X1538805D01*
G01X1507805Y790817D02*
X1508735Y792066D01*
X1509820Y792692D01*
X1511060Y792900D01*
X1512610Y792483D01*
X1513695Y791442D01*
X1514005Y790192D01*
X1513850Y788941D01*
X1513230Y787900D01*
X1510130Y785817D01*
X1508735Y784358D01*
X1507805Y782275D01*
X1507495Y780400D01*
X1514005D01*
G01X1523150Y792900D02*
X1521910Y792483D01*
X1520980Y791442D01*
X1520360Y790192D01*
X1519895Y788525D01*
X1519740Y786650D01*
X1519895Y784775D01*
X1520360Y783108D01*
X1520980Y781858D01*
X1521910Y780817D01*
X1523150Y780400D01*
X1524390Y780817D01*
X1525320Y781858D01*
X1525940Y783108D01*
X1526405Y784775D01*
X1526560Y786650D01*
X1526405Y788525D01*
X1525940Y790192D01*
X1525320Y791442D01*
X1524390Y792483D01*
X1523150Y792900D01*
G01X1532605Y790817D02*
X1533535Y792066D01*
X1534620Y792692D01*
X1535860Y792900D01*
X1537410Y792483D01*
X1538495Y791442D01*
X1538805Y790192D01*
X1538650Y788941D01*
X1538030Y787900D01*
X1534930Y785817D01*
X1533535Y784358D01*
X1532605Y782275D01*
X1532295Y780400D01*
X1538805D01*
G01X1545315Y781858D02*
X1546400Y780817D01*
X1547640Y780400D01*
X1548880Y780817D01*
X1549965Y782066D01*
X1550740Y783942D01*
X1551050Y785817D01*
Y788108D01*
X1550740Y789983D01*
X1549965Y791650D01*
X1549035Y792483D01*
X1547950Y792900D01*
X1546710Y792483D01*
X1545780Y791650D01*
X1545160Y790400D01*
X1544850Y788733D01*
X1545160Y787275D01*
X1545935Y785817D01*
X1546865Y784983D01*
X1547950Y784775D01*
X1549190Y785191D01*
X1550120Y786233D01*
X1551050Y788108D01*
G01X1520205Y757508D02*
X1521290Y758967D01*
X1522220Y759800D01*
X1523460Y760217D01*
X1524545Y759800D01*
X1525320Y758967D01*
X1525940Y757717D01*
X1526095Y756258D01*
X1525940Y755008D01*
X1525320Y753758D01*
X1524390Y752717D01*
X1523305Y752300D01*
X1522065Y752717D01*
X1520980Y753966D01*
X1520360Y755842D01*
X1520205Y757925D01*
X1520515Y760633D01*
X1520980Y762092D01*
X1521755Y763550D01*
X1522840Y764592D01*
X1523925Y764800D01*
X1525010Y764383D01*
X1525785Y763342D01*
G01X1532605Y757508D02*
X1533690Y758967D01*
X1534620Y759800D01*
X1535860Y760217D01*
X1536945Y759800D01*
X1537720Y758967D01*
X1538340Y757717D01*
X1538495Y756258D01*
X1538340Y755008D01*
X1537720Y753758D01*
X1536790Y752717D01*
X1535705Y752300D01*
X1534465Y752717D01*
X1533380Y753966D01*
X1532760Y755842D01*
X1532605Y757925D01*
X1532915Y760633D01*
X1533380Y762092D01*
X1534155Y763550D01*
X1535240Y764592D01*
X1536325Y764800D01*
X1537410Y764383D01*
X1538185Y763342D01*
G01X1516950Y838150D02*
X1515710Y838358D01*
X1514625Y839191D01*
X1513695Y840442D01*
X1513075Y841900D01*
X1512765Y843567D01*
Y845233D01*
X1513075Y846900D01*
X1513695Y848358D01*
X1514625Y849608D01*
X1515710Y850442D01*
X1516950Y850650D01*
X1518190Y850442D01*
X1519275Y849608D01*
X1520205Y848358D01*
X1520825Y846900D01*
X1521135Y845233D01*
Y843567D01*
X1520825Y841900D01*
X1520205Y840442D01*
X1519275Y839191D01*
X1518190Y838358D01*
X1516950Y838150D01*
G01X1518190Y841483D02*
X1520050Y838150D01*
G01X1529350Y850650D02*
Y838150D01*
G01X1525785Y850650D02*
X1532915D01*
G01X1541750Y838150D02*
Y843775D01*
X1538650Y850650D01*
G01X1544850D02*
X1541750Y843775D01*
G01X1514005Y818917D02*
X1514935Y820166D01*
X1516020Y820792D01*
X1517260Y821000D01*
X1518810Y820583D01*
X1519895Y819542D01*
X1520205Y818292D01*
X1520050Y817041D01*
X1519430Y816000D01*
X1516330Y813917D01*
X1514935Y812458D01*
X1514005Y810375D01*
X1513695Y808500D01*
X1520205D01*
G01X1529350D02*
X1530435Y808708D01*
X1531675Y809333D01*
X1532450Y810375D01*
X1532760Y811833D01*
X1532450Y813291D01*
X1531520Y814542D01*
X1530125Y815167D01*
X1528575D01*
X1527645Y815583D01*
X1526870Y816625D01*
X1526560Y818083D01*
X1527025Y819542D01*
X1528110Y820583D01*
X1529350Y821000D01*
X1530590Y820583D01*
X1531675Y819542D01*
X1532140Y818083D01*
X1531830Y816625D01*
X1531055Y815583D01*
X1530125Y815167D01*
X1528575D01*
X1527180Y814542D01*
X1526250Y813291D01*
X1525940Y811833D01*
X1526250Y810375D01*
X1527025Y809333D01*
X1528265Y808708D01*
X1529350Y808500D01*
G01X1543610D02*
Y821000D01*
X1537875Y812042D01*
X1545625D01*
G01X1526405Y144517D02*
X1527335Y145766D01*
X1528420Y146392D01*
X1529660Y146600D01*
X1531210Y146183D01*
X1532295Y145142D01*
X1532605Y143892D01*
X1532450Y142641D01*
X1531830Y141600D01*
X1528730Y139517D01*
X1527335Y138058D01*
X1526405Y135975D01*
X1526095Y134100D01*
X1532605D01*
G01X1526405Y116417D02*
X1527335Y117666D01*
X1528420Y118292D01*
X1529660Y118500D01*
X1531210Y118083D01*
X1532295Y117042D01*
X1532605Y115792D01*
X1532450Y114541D01*
X1531830Y113500D01*
X1528730Y111417D01*
X1527335Y109958D01*
X1526405Y107875D01*
X1526095Y106000D01*
X1532605D01*
G01X1526405Y200717D02*
X1527335Y201966D01*
X1528420Y202592D01*
X1529660Y202800D01*
X1531210Y202383D01*
X1532295Y201342D01*
X1532605Y200092D01*
X1532450Y198841D01*
X1531830Y197800D01*
X1528730Y195717D01*
X1527335Y194258D01*
X1526405Y192175D01*
X1526095Y190300D01*
X1532605D01*
G01X1526405Y172617D02*
X1527335Y173866D01*
X1528420Y174492D01*
X1529660Y174700D01*
X1531210Y174283D01*
X1532295Y173242D01*
X1532605Y171992D01*
X1532450Y170741D01*
X1531830Y169700D01*
X1528730Y167617D01*
X1527335Y166158D01*
X1526405Y164075D01*
X1526095Y162200D01*
X1532605D01*
G01X1529350Y246500D02*
Y259000D01*
X1527490Y256500D01*
G01Y246500D02*
X1531210D01*
G01X1526405Y228817D02*
X1527335Y230066D01*
X1528420Y230692D01*
X1529660Y230900D01*
X1531210Y230483D01*
X1532295Y229442D01*
X1532605Y228192D01*
X1532450Y226941D01*
X1531830Y225900D01*
X1528730Y223817D01*
X1527335Y222358D01*
X1526405Y220275D01*
X1526095Y218400D01*
X1532605D01*
G01X1529350Y330800D02*
Y343300D01*
X1527490Y340800D01*
G01Y330800D02*
X1531210D01*
G01X1529040Y302700D02*
X1529350Y305408D01*
X1529815Y307700D01*
X1530435Y309783D01*
X1531210Y312075D01*
X1532450Y315200D01*
X1526250D01*
G01X1529350Y274600D02*
Y287100D01*
X1527490Y284600D01*
G01Y274600D02*
X1531210D01*
G01X1526405Y397417D02*
X1527335Y398666D01*
X1528420Y399292D01*
X1529660Y399500D01*
X1531210Y399083D01*
X1532295Y398042D01*
X1532605Y396792D01*
X1532450Y395541D01*
X1531830Y394500D01*
X1528730Y392417D01*
X1527335Y390958D01*
X1526405Y388875D01*
X1526095Y387000D01*
X1532605D01*
G01X1529350Y358900D02*
Y371400D01*
X1527490Y368900D01*
G01Y358900D02*
X1531210D01*
G01X1526405Y453617D02*
X1527335Y454866D01*
X1528420Y455492D01*
X1529660Y455700D01*
X1531210Y455283D01*
X1532295Y454242D01*
X1532605Y452992D01*
X1532450Y451741D01*
X1531830Y450700D01*
X1528730Y448617D01*
X1527335Y447158D01*
X1526405Y445075D01*
X1526095Y443200D01*
X1532605D01*
G01X1529350Y415100D02*
Y427600D01*
X1527490Y425100D01*
G01Y415100D02*
X1531210D01*
G01X1526405Y509817D02*
X1527335Y511066D01*
X1528420Y511692D01*
X1529660Y511900D01*
X1531210Y511483D01*
X1532295Y510442D01*
X1532605Y509192D01*
X1532450Y507941D01*
X1531830Y506900D01*
X1528730Y504817D01*
X1527335Y503358D01*
X1526405Y501275D01*
X1526095Y499400D01*
X1532605D01*
G01X1526715Y472758D02*
X1527800Y471717D01*
X1529040Y471300D01*
X1530280Y471717D01*
X1531365Y472966D01*
X1532140Y474842D01*
X1532450Y476717D01*
Y479008D01*
X1532140Y480883D01*
X1531365Y482550D01*
X1530435Y483383D01*
X1529350Y483800D01*
X1528110Y483383D01*
X1527180Y482550D01*
X1526560Y481300D01*
X1526250Y479633D01*
X1526560Y478175D01*
X1527335Y476717D01*
X1528265Y475883D01*
X1529350Y475675D01*
X1530590Y476091D01*
X1531520Y477133D01*
X1532450Y479008D01*
G01X1526715Y585158D02*
X1527800Y584117D01*
X1529040Y583700D01*
X1530280Y584117D01*
X1531365Y585366D01*
X1532140Y587242D01*
X1532450Y589117D01*
Y591408D01*
X1532140Y593283D01*
X1531365Y594950D01*
X1530435Y595783D01*
X1529350Y596200D01*
X1528110Y595783D01*
X1527180Y594950D01*
X1526560Y593700D01*
X1526250Y592033D01*
X1526560Y590575D01*
X1527335Y589117D01*
X1528265Y588283D01*
X1529350Y588075D01*
X1530590Y588491D01*
X1531520Y589533D01*
X1532450Y591408D01*
G01X1526715Y557058D02*
X1527800Y556017D01*
X1529040Y555600D01*
X1530280Y556017D01*
X1531365Y557266D01*
X1532140Y559142D01*
X1532450Y561017D01*
Y563308D01*
X1532140Y565183D01*
X1531365Y566850D01*
X1530435Y567683D01*
X1529350Y568100D01*
X1528110Y567683D01*
X1527180Y566850D01*
X1526560Y565600D01*
X1526250Y563933D01*
X1526560Y562475D01*
X1527335Y561017D01*
X1528265Y560183D01*
X1529350Y559975D01*
X1530590Y560391D01*
X1531520Y561433D01*
X1532450Y563308D01*
G01X3937Y0D02*
X116260D01*
G01X0Y3937D02*
G03X3937Y0I3937J0D01*
G01X0Y723480D02*
Y3937D01*
G01X416Y725241D02*
G03X0Y723480I3521J-1761D01*
G01X18597Y761603D02*
X416Y725241D01*
G01X77756Y98425D02*
G03X63976I-6890J0D01*
G01D02*
G03X77756I6890J0D01*
G01X74697Y254419D02*
X75097Y254819D01*
X75564Y255019D01*
X76097Y255086D01*
X76764Y254953D01*
X77231Y254619D01*
X77364Y254219D01*
X77297Y253819D01*
X77031Y253486D01*
X75697Y252819D01*
X75097Y252353D01*
X74697Y251686D01*
X74564Y251086D01*
X77364D01*
G01X79297Y252753D02*
X79764Y253219D01*
X80164Y253486D01*
X80697Y253619D01*
X81164Y253486D01*
X81497Y253219D01*
X81764Y252819D01*
X81831Y252353D01*
X81764Y251953D01*
X81497Y251553D01*
X81097Y251219D01*
X80631Y251086D01*
X80097Y251219D01*
X79631Y251619D01*
X79364Y252219D01*
X79297Y252886D01*
X79431Y253753D01*
X79631Y254219D01*
X79964Y254686D01*
X80431Y255019D01*
X80897Y255086D01*
X81364Y254953D01*
X81697Y254619D01*
G01X85164Y251086D02*
X85631Y251153D01*
X86164Y251353D01*
X86497Y251686D01*
X86631Y252153D01*
X86497Y252619D01*
X86097Y253019D01*
X85497Y253219D01*
X84831D01*
X84431Y253353D01*
X84097Y253686D01*
X83964Y254153D01*
X84164Y254619D01*
X84631Y254953D01*
X85164Y255086D01*
X85697Y254953D01*
X86164Y254619D01*
X86364Y254153D01*
X86231Y253686D01*
X85897Y253353D01*
X85497Y253219D01*
X84831D01*
X84231Y253019D01*
X83831Y252619D01*
X83697Y252153D01*
X83831Y251686D01*
X84164Y251353D01*
X84697Y251153D01*
X85164Y251086D01*
G01X88364D02*
X91164Y255086D01*
G01X88364D02*
X91164Y251086D01*
G01X94364D02*
Y255086D01*
X93564Y254286D01*
G01Y251086D02*
X95164D01*
G01X97497Y251886D02*
X97897Y251419D01*
X98431Y251153D01*
X99031Y251086D01*
X99564Y251153D01*
X100097Y251486D01*
X100431Y251886D01*
X100497Y252286D01*
X100364Y252753D01*
X99897Y253086D01*
X99431Y253219D01*
X98831D01*
G01X99431D02*
X99831Y253419D01*
X100164Y253753D01*
X100297Y254153D01*
X100164Y254553D01*
X99831Y254886D01*
X99231Y255086D01*
X98631Y255019D01*
X98031Y254753D01*
G01X104364Y251086D02*
Y255086D01*
X101897Y252219D01*
X105231D01*
G01X83071Y245079D02*
G03Y231693I0J-6693D01*
G01X77756Y472441D02*
G03X63976I-6890J0D01*
G01D02*
G03X77756I6890J0D01*
G01X57087Y740157D02*
G03X41339I-7874J0D01*
G01D02*
G03X57087I7874J0D01*
G01X22118Y763780D02*
G03X18597Y761603I1J-3937D01*
G01X386149Y763780D02*
X22118D01*
G01X128071Y3937D02*
G03X132008Y0I3937J0D01*
G01X116260D02*
G03X120197Y3937I0J3937D01*
G01X132008Y0D02*
X275709D01*
G01X120197Y3937D02*
Y429331D01*
G01X128071Y59055D02*
Y3937D01*
G01Y59055D02*
G03X120197I-3937J0D01*
G01X128071D02*
G03X120197I-3937J0D01*
G01X128071Y98425D02*
Y421457D01*
G01X120197Y98425D02*
G03X128071I3937J0D01*
G01X120197D02*
G03X128071I3937J0D01*
G01X96457Y231693D02*
G03Y245079I0J6693D01*
G01X83071D02*
X96457D01*
G01Y231693D02*
X83071D01*
G01X96654Y413583D02*
G03X83661I-6496J0D01*
G01D02*
G03X96654I6496J0D01*
G01X132008Y425394D02*
G03X128071Y421457I0J-3937D01*
G01X124134Y433268D02*
X283583D01*
G01X124134D02*
G03X120197Y429331I0J-3937D01*
G01X184173Y425394D02*
X132008D01*
G01X213480Y37075D02*
G03I-4291J0D01*
G01Y383483D02*
G03I-4291J0D01*
G01X184173Y425394D02*
G03Y433268I0J3937D01*
G01Y425394D02*
G03Y433268I0J3937D01*
G01X171457Y669291D02*
G03X154921I-8268J0D01*
G01D02*
G03X171457I8268J0D01*
G01X223543Y425394D02*
X275709D01*
G01X223543Y433268D02*
G03Y425394I0J-3937D01*
G01Y433268D02*
G03Y425394I0J-3937D01*
G01X275709Y0D02*
G03X279646Y3937I0J3937D01*
G01X291457Y0D02*
X921260D01*
G01X287520Y3937D02*
G03X291457Y0I3937J0D01*
G01X321164Y67453D02*
X321564Y66986D01*
X322098Y66720D01*
X322698Y66653D01*
X323231Y66720D01*
X323764Y67053D01*
X324098Y67453D01*
X324164Y67853D01*
X324031Y68320D01*
X323564Y68653D01*
X323098Y68786D01*
X322498D01*
G01X323098D02*
X323498Y68986D01*
X323831Y69320D01*
X323964Y69720D01*
X323831Y70120D01*
X323498Y70453D01*
X322898Y70653D01*
X322298Y70586D01*
X321698Y70320D01*
G01X325964Y69986D02*
X326364Y70386D01*
X326831Y70586D01*
X327364Y70653D01*
X328031Y70520D01*
X328498Y70186D01*
X328631Y69786D01*
X328564Y69386D01*
X328298Y69053D01*
X326964Y68386D01*
X326364Y67920D01*
X325964Y67253D01*
X325831Y66653D01*
X328631D01*
G01X330431D02*
X333231Y70653D01*
G01X330431D02*
X333231Y66653D01*
G01X336431D02*
X336898Y66720D01*
X337431Y66920D01*
X337764Y67253D01*
X337898Y67720D01*
X337764Y68186D01*
X337364Y68586D01*
X336764Y68786D01*
X336098D01*
X335698Y68920D01*
X335364Y69253D01*
X335231Y69720D01*
X335431Y70186D01*
X335898Y70520D01*
X336431Y70653D01*
X336964Y70520D01*
X337431Y70186D01*
X337631Y69720D01*
X337498Y69253D01*
X337164Y68920D01*
X336764Y68786D01*
X336098D01*
X335498Y68586D01*
X335098Y68186D01*
X334964Y67720D01*
X335098Y67253D01*
X335431Y66920D01*
X335964Y66720D01*
X336431Y66653D01*
G01X339564Y67453D02*
X339964Y66986D01*
X340498Y66720D01*
X341098Y66653D01*
X341631Y66720D01*
X342164Y67053D01*
X342498Y67453D01*
X342564Y67853D01*
X342431Y68320D01*
X341964Y68653D01*
X341498Y68786D01*
X340898D01*
G01X341498D02*
X341898Y68986D01*
X342231Y69320D01*
X342364Y69720D01*
X342231Y70120D01*
X341898Y70453D01*
X341298Y70653D01*
X340698Y70586D01*
X340098Y70320D01*
G01X287520Y429331D02*
Y3937D01*
G01X279646Y59055D02*
Y3937D01*
G01X287520Y59055D02*
G03X279646I-3937J0D01*
G01X287520D02*
G03X279646I-3937J0D01*
G01X321114Y72979D02*
X321514Y72512D01*
X322048Y72246D01*
X322648Y72179D01*
X323181Y72246D01*
X323714Y72579D01*
X324048Y72979D01*
X324114Y73379D01*
X323981Y73846D01*
X323514Y74179D01*
X323048Y74312D01*
X322448D01*
G01X323048D02*
X323448Y74512D01*
X323781Y74846D01*
X323914Y75246D01*
X323781Y75646D01*
X323448Y75979D01*
X322848Y76179D01*
X322248Y76112D01*
X321648Y75846D01*
G01X325914Y75512D02*
X326314Y75912D01*
X326781Y76112D01*
X327314Y76179D01*
X327981Y76046D01*
X328448Y75712D01*
X328581Y75312D01*
X328514Y74912D01*
X328248Y74579D01*
X326914Y73912D01*
X326314Y73446D01*
X325914Y72779D01*
X325781Y72179D01*
X328581D01*
G01X330381D02*
X333181Y76179D01*
G01X330381D02*
X333181Y72179D01*
G01X334914Y72779D02*
X335314Y72446D01*
X335781Y72246D01*
X336381Y72179D01*
X336981Y72312D01*
X337448Y72579D01*
X337781Y73046D01*
X337848Y73579D01*
X337714Y74112D01*
X337381Y74446D01*
X336914Y74712D01*
X336448Y74779D01*
X335981Y74712D01*
X335381Y74446D01*
X335581Y76179D01*
X337381D01*
G01X339714Y73846D02*
X340181Y74312D01*
X340581Y74579D01*
X341114Y74712D01*
X341581Y74579D01*
X341914Y74312D01*
X342181Y73912D01*
X342248Y73446D01*
X342181Y73046D01*
X341914Y72646D01*
X341514Y72312D01*
X341048Y72179D01*
X340514Y72312D01*
X340048Y72712D01*
X339781Y73312D01*
X339714Y73979D01*
X339848Y74846D01*
X340048Y75312D01*
X340381Y75779D01*
X340848Y76112D01*
X341314Y76179D01*
X341781Y76046D01*
X342114Y75712D01*
G01X279646Y98425D02*
Y421457D01*
G01Y98425D02*
G03X287520I3937J0D01*
G01X279646D02*
G03X287520I3937J0D01*
G01X315551Y157677D02*
G03X302559I-6496J0D01*
G01D02*
G03X315551I6496J0D01*
G01X294185Y429616D02*
X294585Y430016D01*
X295052Y430216D01*
X295585Y430283D01*
X296252Y430150D01*
X296719Y429816D01*
X296852Y429416D01*
X296785Y429016D01*
X296519Y428683D01*
X295185Y428016D01*
X294585Y427550D01*
X294185Y426883D01*
X294052Y426283D01*
X296852D01*
G01X298785Y427950D02*
X299252Y428416D01*
X299652Y428683D01*
X300185Y428816D01*
X300652Y428683D01*
X300985Y428416D01*
X301252Y428016D01*
X301319Y427550D01*
X301252Y427150D01*
X300985Y426750D01*
X300585Y426416D01*
X300119Y426283D01*
X299585Y426416D01*
X299119Y426816D01*
X298852Y427416D01*
X298785Y428083D01*
X298919Y428950D01*
X299119Y429416D01*
X299452Y429883D01*
X299919Y430216D01*
X300385Y430283D01*
X300852Y430150D01*
X301185Y429816D01*
G01X304652Y426283D02*
X305119Y426350D01*
X305652Y426550D01*
X305985Y426883D01*
X306119Y427350D01*
X305985Y427816D01*
X305585Y428216D01*
X304985Y428416D01*
X304319D01*
X303919Y428550D01*
X303585Y428883D01*
X303452Y429350D01*
X303652Y429816D01*
X304119Y430150D01*
X304652Y430283D01*
X305185Y430150D01*
X305652Y429816D01*
X305852Y429350D01*
X305719Y428883D01*
X305385Y428550D01*
X304985Y428416D01*
X304319D01*
X303719Y428216D01*
X303319Y427816D01*
X303185Y427350D01*
X303319Y426883D01*
X303652Y426550D01*
X304185Y426350D01*
X304652Y426283D01*
G01X307852D02*
X310652Y430283D01*
G01X307852D02*
X310652Y426283D01*
G01X313852D02*
Y430283D01*
X313052Y429483D01*
G01Y426283D02*
X314652D01*
G01X316985Y427083D02*
X317385Y426616D01*
X317919Y426350D01*
X318519Y426283D01*
X319052Y426350D01*
X319585Y426683D01*
X319919Y427083D01*
X319985Y427483D01*
X319852Y427950D01*
X319385Y428283D01*
X318919Y428416D01*
X318319D01*
G01X318919D02*
X319319Y428616D01*
X319652Y428950D01*
X319785Y429350D01*
X319652Y429750D01*
X319319Y430083D01*
X318719Y430283D01*
X318119Y430216D01*
X317519Y429950D01*
G01X323852Y426283D02*
Y430283D01*
X321385Y427416D01*
X324719D01*
G01X315945Y406890D02*
G03Y420276I0J6693D01*
G01X302559D02*
X315945D01*
G01X302559D02*
G03Y406890I0J-6693D01*
G01X315945D02*
X302559D01*
G01X279646Y421457D02*
G03X275709Y425394I-3937J0D01*
G01X287520Y429331D02*
G03X283583Y433268I-3937J0D01*
G01X321850Y472441D02*
G03X308071I-6889J0D01*
G01D02*
G03X321850I6889J0D01*
G01X357402Y66953D02*
X357802Y66486D01*
X358336Y66220D01*
X358936Y66153D01*
X359469Y66220D01*
X360002Y66553D01*
X360336Y66953D01*
X360402Y67353D01*
X360269Y67820D01*
X359802Y68153D01*
X359336Y68286D01*
X358736D01*
G01X359336D02*
X359736Y68486D01*
X360069Y68820D01*
X360202Y69220D01*
X360069Y69620D01*
X359736Y69953D01*
X359136Y70153D01*
X358536Y70086D01*
X357936Y69820D01*
G01X362202Y69486D02*
X362602Y69886D01*
X363069Y70086D01*
X363602Y70153D01*
X364269Y70020D01*
X364736Y69686D01*
X364869Y69286D01*
X364802Y68886D01*
X364536Y68553D01*
X363202Y67886D01*
X362602Y67420D01*
X362202Y66753D01*
X362069Y66153D01*
X364869D01*
G01X366669D02*
X369469Y70153D01*
G01X366669D02*
X369469Y66153D01*
G01X371202Y66753D02*
X371602Y66420D01*
X372069Y66220D01*
X372669Y66153D01*
X373269Y66286D01*
X373736Y66553D01*
X374069Y67020D01*
X374136Y67553D01*
X374002Y68086D01*
X373669Y68420D01*
X373202Y68686D01*
X372736Y68753D01*
X372269Y68686D01*
X371669Y68420D01*
X371869Y70153D01*
X373669D01*
G01X376002Y67820D02*
X376469Y68286D01*
X376869Y68553D01*
X377402Y68686D01*
X377869Y68553D01*
X378202Y68286D01*
X378469Y67886D01*
X378536Y67420D01*
X378469Y67020D01*
X378202Y66620D01*
X377802Y66286D01*
X377336Y66153D01*
X376802Y66286D01*
X376336Y66686D01*
X376069Y67286D01*
X376002Y67953D01*
X376136Y68820D01*
X376336Y69286D01*
X376669Y69753D01*
X377136Y70086D01*
X377602Y70153D01*
X378069Y70020D01*
X378402Y69686D01*
G01X412402Y39370D02*
G03X398622I-6890J0D01*
G01D02*
G03X412402I6890J0D01*
G01X357252Y72479D02*
X357652Y72012D01*
X358186Y71746D01*
X358786Y71679D01*
X359319Y71746D01*
X359852Y72079D01*
X360186Y72479D01*
X360252Y72879D01*
X360119Y73346D01*
X359652Y73679D01*
X359186Y73812D01*
X358586D01*
G01X359186D02*
X359586Y74012D01*
X359919Y74346D01*
X360052Y74746D01*
X359919Y75146D01*
X359586Y75479D01*
X358986Y75679D01*
X358386Y75612D01*
X357786Y75346D01*
G01X362052Y75012D02*
X362452Y75412D01*
X362919Y75612D01*
X363452Y75679D01*
X364119Y75546D01*
X364586Y75212D01*
X364719Y74812D01*
X364652Y74412D01*
X364386Y74079D01*
X363052Y73412D01*
X362452Y72946D01*
X362052Y72279D01*
X361919Y71679D01*
X364719D01*
G01X366519D02*
X369319Y75679D01*
G01X366519D02*
X369319Y71679D01*
G01X372519D02*
X372986Y71746D01*
X373519Y71946D01*
X373852Y72279D01*
X373986Y72746D01*
X373852Y73212D01*
X373452Y73612D01*
X372852Y73812D01*
X372186D01*
X371786Y73946D01*
X371452Y74279D01*
X371319Y74746D01*
X371519Y75212D01*
X371986Y75546D01*
X372519Y75679D01*
X373052Y75546D01*
X373519Y75212D01*
X373719Y74746D01*
X373586Y74279D01*
X373252Y73946D01*
X372852Y73812D01*
X372186D01*
X371586Y73612D01*
X371186Y73212D01*
X371052Y72746D01*
X371186Y72279D01*
X371519Y71946D01*
X372052Y71746D01*
X372519Y71679D01*
G01X375652Y72479D02*
X376052Y72012D01*
X376586Y71746D01*
X377186Y71679D01*
X377719Y71746D01*
X378252Y72079D01*
X378586Y72479D01*
X378652Y72879D01*
X378519Y73346D01*
X378052Y73679D01*
X377586Y73812D01*
X376986D01*
G01X377586D02*
X377986Y74012D01*
X378319Y74346D01*
X378452Y74746D01*
X378319Y75146D01*
X377986Y75479D01*
X377386Y75679D01*
X376786Y75612D01*
X376186Y75346D01*
G01X595332Y198516D02*
Y194516D01*
X593732D01*
X593199Y194716D01*
X592799Y195183D01*
X592666Y195716D01*
X592799Y196249D01*
X593132Y196649D01*
X593732Y196849D01*
X595332D01*
G01X590332Y198516D02*
Y195849D01*
G01Y196383D02*
X589999Y196116D01*
X589666Y195916D01*
X589199Y195849D01*
X588866Y195916D01*
X588466Y196116D01*
G01X585799Y196716D02*
X583666D01*
X583866Y196249D01*
X584199Y195983D01*
X584666Y195849D01*
X585132Y195916D01*
X585532Y196116D01*
X585799Y196583D01*
X585932Y196983D01*
Y197383D01*
X585799Y197783D01*
X585466Y198183D01*
X585066Y198449D01*
X584599Y198516D01*
X584132Y198383D01*
X583666Y197983D01*
G01X581199Y198049D02*
X580866Y198316D01*
X580399Y198516D01*
X579999D01*
X579599Y198383D01*
X579332Y198183D01*
X579199Y197916D01*
X579266Y197516D01*
X579532Y197316D01*
X580732Y196916D01*
X580999Y196449D01*
X580866Y196116D01*
X580599Y195916D01*
X580199Y195849D01*
X579799Y195916D01*
X579399Y196116D01*
G01X576599Y198049D02*
X576266Y198316D01*
X575799Y198516D01*
X575399D01*
X574999Y198383D01*
X574732Y198183D01*
X574599Y197916D01*
X574666Y197516D01*
X574932Y197316D01*
X576132Y196916D01*
X576399Y196449D01*
X576266Y196116D01*
X575999Y195916D01*
X575599Y195849D01*
X575199Y195916D01*
X574799Y196116D01*
G01X571866Y197183D02*
X570132D01*
G01X566799Y198516D02*
Y195116D01*
X566666Y194783D01*
X566399Y194583D01*
X565999Y194516D01*
X565599Y194649D01*
X565399Y194983D01*
G01X566199Y196116D02*
X567532D01*
G01X561799Y195849D02*
Y198516D01*
G01Y194783D02*
X561932Y194716D01*
Y194583D01*
X561799Y194516D01*
X561666Y194583D01*
Y194716D01*
X561799Y194783D01*
G01X557199Y194516D02*
Y198516D01*
G01X558132Y195849D02*
X556266D01*
G01X549332Y198516D02*
Y194516D01*
X547732D01*
X547199Y194716D01*
X546799Y195183D01*
X546666Y195716D01*
X546799Y196249D01*
X547132Y196649D01*
X547732Y196849D01*
X549332D01*
G01X543399Y194516D02*
Y198516D01*
G01X544932Y194516D02*
X541866D01*
G01X540199Y198516D02*
Y194516D01*
G01X537399D02*
Y198516D01*
G01Y196516D02*
X540199D01*
G01X530732Y198516D02*
Y194516D01*
G01X528599Y195849D02*
X530732Y197383D01*
G01X529866Y196783D02*
X528466Y198516D01*
G01X525999Y196716D02*
X523866D01*
X524066Y196249D01*
X524399Y195983D01*
X524866Y195849D01*
X525332Y195916D01*
X525732Y196116D01*
X525999Y196583D01*
X526132Y196983D01*
Y197383D01*
X525999Y197783D01*
X525666Y198183D01*
X525266Y198449D01*
X524799Y198516D01*
X524332Y198383D01*
X523866Y197983D01*
G01X521399Y196716D02*
X519266D01*
X519466Y196249D01*
X519799Y195983D01*
X520266Y195849D01*
X520732Y195916D01*
X521132Y196116D01*
X521399Y196583D01*
X521532Y196983D01*
Y197383D01*
X521399Y197783D01*
X521066Y198183D01*
X520666Y198449D01*
X520199Y198516D01*
X519732Y198383D01*
X519266Y197983D01*
G01X516999Y199849D02*
Y195849D01*
G01Y196449D02*
X516666Y196116D01*
X516332Y195916D01*
X515799Y195849D01*
X515332Y195916D01*
X514866Y196249D01*
X514666Y196716D01*
X514599Y197183D01*
X514666Y197649D01*
X514866Y198116D01*
X515266Y198383D01*
X515799Y198516D01*
X516266Y198449D01*
X516732Y198249D01*
X516999Y197983D01*
G01X507732Y198516D02*
Y194516D01*
G01Y196449D02*
X507399Y196116D01*
X507066Y195916D01*
X506532Y195849D01*
X506132Y195916D01*
X505666Y196183D01*
X505466Y196583D01*
Y198516D01*
G01X501999D02*
X502399Y198449D01*
X502799Y198183D01*
X503066Y197716D01*
X503199Y197183D01*
X503066Y196649D01*
X502799Y196183D01*
X502399Y195916D01*
X501999Y195849D01*
X501599Y195916D01*
X501199Y196183D01*
X500932Y196649D01*
X500866Y197183D01*
X500932Y197716D01*
X501199Y198183D01*
X501599Y198449D01*
X501999Y198516D01*
G01X497399D02*
Y194516D01*
G01X493799Y196716D02*
X491666D01*
X491866Y196249D01*
X492199Y195983D01*
X492666Y195849D01*
X493132Y195916D01*
X493532Y196116D01*
X493799Y196583D01*
X493932Y196983D01*
Y197383D01*
X493799Y197783D01*
X493466Y198183D01*
X493066Y198449D01*
X492599Y198516D01*
X492132Y198383D01*
X491666Y197983D01*
G01X484599Y198049D02*
X484266Y198316D01*
X483799Y198516D01*
X483399D01*
X482999Y198383D01*
X482732Y198183D01*
X482599Y197916D01*
X482666Y197516D01*
X482932Y197316D01*
X484132Y196916D01*
X484399Y196449D01*
X484266Y196116D01*
X483999Y195916D01*
X483599Y195849D01*
X483199Y195916D01*
X482799Y196116D01*
G01X478999Y195849D02*
Y198516D01*
G01Y194783D02*
X479132Y194716D01*
Y194583D01*
X478999Y194516D01*
X478866Y194583D01*
Y194716D01*
X478999Y194783D01*
G01X475399Y195849D02*
X473399D01*
X475399Y198516D01*
X473399D01*
G01X470799Y196716D02*
X468666D01*
X468866Y196249D01*
X469199Y195983D01*
X469666Y195849D01*
X470132Y195916D01*
X470532Y196116D01*
X470799Y196583D01*
X470932Y196983D01*
Y197383D01*
X470799Y197783D01*
X470466Y198183D01*
X470066Y198449D01*
X469599Y198516D01*
X469132Y198383D01*
X468666Y197983D01*
G01X460599Y194516D02*
Y198516D01*
G01X461532Y195849D02*
X459666D01*
G01X455999Y198516D02*
X456399Y198449D01*
X456799Y198183D01*
X457066Y197716D01*
X457199Y197183D01*
X457066Y196649D01*
X456799Y196183D01*
X456399Y195916D01*
X455999Y195849D01*
X455599Y195916D01*
X455199Y196183D01*
X454932Y196649D01*
X454866Y197183D01*
X454932Y197716D01*
X455199Y198183D01*
X455599Y198449D01*
X455999Y198516D01*
G01X451399D02*
Y194516D01*
G01X447799Y196716D02*
X445666D01*
X445866Y196249D01*
X446199Y195983D01*
X446666Y195849D01*
X447132Y195916D01*
X447532Y196116D01*
X447799Y196583D01*
X447932Y196983D01*
Y197383D01*
X447799Y197783D01*
X447466Y198183D01*
X447066Y198449D01*
X446599Y198516D01*
X446132Y198383D01*
X445666Y197983D01*
G01X443132Y198516D02*
Y195849D01*
G01Y196383D02*
X442799Y196116D01*
X442466Y195916D01*
X441999Y195849D01*
X441666Y195916D01*
X441266Y196116D01*
G01X436399Y198516D02*
Y195849D01*
G01Y196316D02*
X436666Y196049D01*
X437066Y195916D01*
X437532Y195849D01*
X437999Y195983D01*
X438399Y196249D01*
X438666Y196649D01*
X438799Y197183D01*
X438666Y197716D01*
X438399Y198116D01*
X437999Y198383D01*
X437532Y198516D01*
X437066Y198449D01*
X436666Y198249D01*
X436399Y197983D01*
G01X434132Y198516D02*
Y195849D01*
G01Y196516D02*
X433866Y196183D01*
X433466Y195916D01*
X432932Y195849D01*
X432466Y195916D01*
X432066Y196183D01*
X431866Y196649D01*
Y198516D01*
G01X427332Y196183D02*
X427799Y195916D01*
X428199Y195849D01*
X428732Y195983D01*
X429132Y196249D01*
X429399Y196716D01*
X429466Y197183D01*
X429399Y197649D01*
X429132Y198049D01*
X428732Y198383D01*
X428199Y198516D01*
X427732Y198383D01*
X427332Y198116D01*
G01X424799Y196716D02*
X422666D01*
X422866Y196249D01*
X423199Y195983D01*
X423666Y195849D01*
X424132Y195916D01*
X424532Y196116D01*
X424799Y196583D01*
X424932Y196983D01*
Y197383D01*
X424799Y197783D01*
X424466Y198183D01*
X424066Y198449D01*
X423599Y198516D01*
X423132Y198383D01*
X422666Y197983D01*
G01X415332Y197183D02*
X413732D01*
G01X414599Y196316D02*
Y198049D01*
G01X411199Y198649D02*
X408799Y194516D01*
G01X406266Y197183D02*
X404532D01*
G01X402066Y195183D02*
X401666Y194783D01*
X401199Y194583D01*
X400666Y194516D01*
X399999Y194649D01*
X399532Y194983D01*
X399399Y195383D01*
X399466Y195783D01*
X399732Y196116D01*
X401066Y196783D01*
X401666Y197249D01*
X402066Y197916D01*
X402199Y198516D01*
X399399D01*
G01X393599D02*
Y195849D01*
G01Y196583D02*
X393399Y196249D01*
X393066Y195983D01*
X392599Y195849D01*
X392132Y195983D01*
X391799Y196249D01*
X391599Y196583D01*
Y198516D01*
G01Y196583D02*
X391399Y196249D01*
X391066Y195983D01*
X390599Y195849D01*
X390132Y195983D01*
X389799Y196249D01*
X389599Y196649D01*
Y198516D01*
G01X386999Y195849D02*
Y198516D01*
G01Y194783D02*
X387132Y194716D01*
Y194583D01*
X386999Y194516D01*
X386866Y194583D01*
Y194716D01*
X386999Y194783D01*
G01X382399Y198516D02*
Y194516D01*
G01X378799Y198049D02*
X378466Y198316D01*
X377999Y198516D01*
X377599D01*
X377199Y198383D01*
X376932Y198183D01*
X376799Y197916D01*
X376866Y197516D01*
X377132Y197316D01*
X378332Y196916D01*
X378599Y196449D01*
X378466Y196116D01*
X378199Y195916D01*
X377799Y195849D01*
X377399Y195916D01*
X376999Y196116D01*
G01X371063Y740157D02*
G03X357283I-6890J0D01*
G01D02*
G03X371063I6890J0D01*
G01X403756Y763780D02*
G03X400235Y758082I0J-3937D01*
G01X389671Y761603D02*
G03X386149Y763780I-3522J-1760D01*
G01X414895Y728762D02*
X400235Y758082D01*
G01X407852Y725241D02*
X389671Y761603D01*
G01X403756Y763780D02*
X428096D01*
G01X558799Y119154D02*
X419153D01*
Y185571D01*
X558799D01*
Y119154D01*
G01X562299Y188977D02*
X414299D01*
G01X416142Y200787D02*
G03X420079Y196850I3937J0D01*
G01X408268Y188976D02*
Y723480D01*
G01Y188976D02*
G03X412205I1968J0D01*
G01X556299Y196850D02*
X420079D01*
G01X564173Y188976D02*
X412205D01*
G01X416142Y316929D02*
Y200787D01*
G01Y316929D02*
G03X408268I-3937J0D01*
G01X416142D02*
G03X408268I-3937J0D01*
G01X416142Y347638D02*
Y690803D01*
G01X408268Y347638D02*
G03X416142I3937J0D01*
G01X408268D02*
G03X416142I3937J0D01*
G01Y721512D02*
Y723481D01*
G01Y723482D02*
G03X414894Y728764I-11811J-2D01*
G01X408268Y723480D02*
G03X407852Y725241I-3937J0D01*
G01X408268Y721512D02*
G03X416142I3937J0D01*
G01Y690803D02*
G03X408268I-3937J0D01*
G01Y721512D02*
G03X416142I3937J0D01*
G01Y690803D02*
G03X408268I-3937J0D01*
G01X428096Y763780D02*
G03X435970I3937J0D01*
G01D02*
X572622D01*
G01X522363Y3038D02*
Y7038D01*
X523963D01*
X524496Y6838D01*
X524896Y6371D01*
X525029Y5838D01*
X524896Y5305D01*
X524563Y4905D01*
X523963Y4705D01*
X522363D01*
G01X527363Y3038D02*
Y5705D01*
G01Y5171D02*
X527696Y5438D01*
X528029Y5638D01*
X528496Y5705D01*
X528829Y5638D01*
X529229Y5438D01*
G01X531896Y4838D02*
X534029D01*
X533829Y5305D01*
X533496Y5571D01*
X533029Y5705D01*
X532563Y5638D01*
X532163Y5438D01*
X531896Y4971D01*
X531763Y4571D01*
Y4171D01*
X531896Y3771D01*
X532229Y3371D01*
X532629Y3105D01*
X533096Y3038D01*
X533563Y3171D01*
X534029Y3571D01*
G01X536496Y3505D02*
X536829Y3238D01*
X537296Y3038D01*
X537696D01*
X538096Y3171D01*
X538363Y3371D01*
X538496Y3638D01*
X538429Y4038D01*
X538163Y4238D01*
X536963Y4638D01*
X536696Y5105D01*
X536829Y5438D01*
X537096Y5638D01*
X537496Y5705D01*
X537896Y5638D01*
X538296Y5438D01*
G01X541096Y3505D02*
X541429Y3238D01*
X541896Y3038D01*
X542296D01*
X542696Y3171D01*
X542963Y3371D01*
X543096Y3638D01*
X543029Y4038D01*
X542763Y4238D01*
X541563Y4638D01*
X541296Y5105D01*
X541429Y5438D01*
X541696Y5638D01*
X542096Y5705D01*
X542496Y5638D01*
X542896Y5438D01*
G01X545829Y4371D02*
X547563D01*
G01X550896Y3038D02*
Y6438D01*
X551029Y6771D01*
X551296Y6971D01*
X551696Y7038D01*
X552096Y6905D01*
X552296Y6571D01*
G01X551496Y5438D02*
X550163D01*
G01X555896Y5705D02*
Y3038D01*
G01Y6771D02*
X555763Y6838D01*
Y6971D01*
X555896Y7038D01*
X556029Y6971D01*
Y6838D01*
X555896Y6771D01*
G01X560496Y7038D02*
Y3038D01*
G01X559563Y5705D02*
X561429D01*
G01X568363Y3038D02*
Y7038D01*
X569963D01*
X570496Y6838D01*
X570896Y6371D01*
X571029Y5838D01*
X570896Y5305D01*
X570563Y4905D01*
X569963Y4705D01*
X568363D01*
G01X574296Y7038D02*
Y3038D01*
G01X572763Y7038D02*
X575829D01*
G01X577496Y3038D02*
Y7038D01*
G01X580296D02*
Y3038D01*
G01Y5038D02*
X577496D01*
G01X586963Y3038D02*
Y7038D01*
G01X589096Y5705D02*
X586963Y4171D01*
G01X587829Y4771D02*
X589229Y3038D01*
G01X591696Y4838D02*
X593829D01*
X593629Y5305D01*
X593296Y5571D01*
X592829Y5705D01*
X592363Y5638D01*
X591963Y5438D01*
X591696Y4971D01*
X591563Y4571D01*
Y4171D01*
X591696Y3771D01*
X592029Y3371D01*
X592429Y3105D01*
X592896Y3038D01*
X593363Y3171D01*
X593829Y3571D01*
G01X596296Y4838D02*
X598429D01*
X598229Y5305D01*
X597896Y5571D01*
X597429Y5705D01*
X596963Y5638D01*
X596563Y5438D01*
X596296Y4971D01*
X596163Y4571D01*
Y4171D01*
X596296Y3771D01*
X596629Y3371D01*
X597029Y3105D01*
X597496Y3038D01*
X597963Y3171D01*
X598429Y3571D01*
G01X600696Y1705D02*
Y5705D01*
G01Y5105D02*
X601029Y5438D01*
X601363Y5638D01*
X601896Y5705D01*
X602363Y5638D01*
X602829Y5305D01*
X603029Y4838D01*
X603096Y4371D01*
X603029Y3905D01*
X602829Y3438D01*
X602429Y3171D01*
X601896Y3038D01*
X601429Y3105D01*
X600963Y3305D01*
X600696Y3571D01*
G01X609963Y3038D02*
Y7038D01*
G01Y5105D02*
X610296Y5438D01*
X610629Y5638D01*
X611163Y5705D01*
X611563Y5638D01*
X612029Y5371D01*
X612229Y4971D01*
Y3038D01*
G01X615696D02*
X615296Y3105D01*
X614896Y3371D01*
X614629Y3838D01*
X614496Y4371D01*
X614629Y4905D01*
X614896Y5371D01*
X615296Y5638D01*
X615696Y5705D01*
X616096Y5638D01*
X616496Y5371D01*
X616763Y4905D01*
X616829Y4371D01*
X616763Y3838D01*
X616496Y3371D01*
X616096Y3105D01*
X615696Y3038D01*
G01X620296D02*
Y7038D01*
G01X623896Y4838D02*
X626029D01*
X625829Y5305D01*
X625496Y5571D01*
X625029Y5705D01*
X624563Y5638D01*
X624163Y5438D01*
X623896Y4971D01*
X623763Y4571D01*
Y4171D01*
X623896Y3771D01*
X624229Y3371D01*
X624629Y3105D01*
X625096Y3038D01*
X625563Y3171D01*
X626029Y3571D01*
G01X633096Y3505D02*
X633429Y3238D01*
X633896Y3038D01*
X634296D01*
X634696Y3171D01*
X634963Y3371D01*
X635096Y3638D01*
X635029Y4038D01*
X634763Y4238D01*
X633563Y4638D01*
X633296Y5105D01*
X633429Y5438D01*
X633696Y5638D01*
X634096Y5705D01*
X634496Y5638D01*
X634896Y5438D01*
G01X638696Y5705D02*
Y3038D01*
G01Y6771D02*
X638563Y6838D01*
Y6971D01*
X638696Y7038D01*
X638829Y6971D01*
Y6838D01*
X638696Y6771D01*
G01X642296Y5705D02*
X644296D01*
X642296Y3038D01*
X644296D01*
G01X646896Y4838D02*
X649029D01*
X648829Y5305D01*
X648496Y5571D01*
X648029Y5705D01*
X647563Y5638D01*
X647163Y5438D01*
X646896Y4971D01*
X646763Y4571D01*
Y4171D01*
X646896Y3771D01*
X647229Y3371D01*
X647629Y3105D01*
X648096Y3038D01*
X648563Y3171D01*
X649029Y3571D01*
G01X657096Y7038D02*
Y3038D01*
G01X656163Y5705D02*
X658029D01*
G01X661696Y3038D02*
X661296Y3105D01*
X660896Y3371D01*
X660629Y3838D01*
X660496Y4371D01*
X660629Y4905D01*
X660896Y5371D01*
X661296Y5638D01*
X661696Y5705D01*
X662096Y5638D01*
X662496Y5371D01*
X662763Y4905D01*
X662829Y4371D01*
X662763Y3838D01*
X662496Y3371D01*
X662096Y3105D01*
X661696Y3038D01*
G01X666296D02*
Y7038D01*
G01X669896Y4838D02*
X672029D01*
X671829Y5305D01*
X671496Y5571D01*
X671029Y5705D01*
X670563Y5638D01*
X670163Y5438D01*
X669896Y4971D01*
X669763Y4571D01*
Y4171D01*
X669896Y3771D01*
X670229Y3371D01*
X670629Y3105D01*
X671096Y3038D01*
X671563Y3171D01*
X672029Y3571D01*
G01X674563Y3038D02*
Y5705D01*
G01Y5171D02*
X674896Y5438D01*
X675229Y5638D01*
X675696Y5705D01*
X676029Y5638D01*
X676429Y5438D01*
G01X681296Y3038D02*
Y5705D01*
G01Y5238D02*
X681029Y5505D01*
X680629Y5638D01*
X680163Y5705D01*
X679696Y5571D01*
X679296Y5305D01*
X679029Y4905D01*
X678896Y4371D01*
X679029Y3838D01*
X679296Y3438D01*
X679696Y3171D01*
X680163Y3038D01*
X680629Y3105D01*
X681029Y3305D01*
X681296Y3571D01*
G01X683563Y3038D02*
Y5705D01*
G01Y5038D02*
X683829Y5371D01*
X684229Y5638D01*
X684763Y5705D01*
X685229Y5638D01*
X685629Y5371D01*
X685829Y4905D01*
Y3038D01*
G01X690363Y5371D02*
X689896Y5638D01*
X689496Y5705D01*
X688963Y5571D01*
X688563Y5305D01*
X688296Y4838D01*
X688229Y4371D01*
X688296Y3905D01*
X688563Y3505D01*
X688963Y3171D01*
X689496Y3038D01*
X689963Y3171D01*
X690363Y3438D01*
G01X692896Y4838D02*
X695029D01*
X694829Y5305D01*
X694496Y5571D01*
X694029Y5705D01*
X693563Y5638D01*
X693163Y5438D01*
X692896Y4971D01*
X692763Y4571D01*
Y4171D01*
X692896Y3771D01*
X693229Y3371D01*
X693629Y3105D01*
X694096Y3038D01*
X694563Y3171D01*
X695029Y3571D01*
G01X702363Y4371D02*
X703963D01*
G01X703096Y5238D02*
Y3505D01*
G01X706496Y2905D02*
X708896Y7038D01*
G01X711429Y4371D02*
X713163D01*
G01X715629Y6371D02*
X716029Y6771D01*
X716496Y6971D01*
X717029Y7038D01*
X717696Y6905D01*
X718163Y6571D01*
X718296Y6171D01*
X718229Y5771D01*
X717963Y5438D01*
X716629Y4771D01*
X716029Y4305D01*
X715629Y3638D01*
X715496Y3038D01*
X718296D01*
G01X719496D02*
Y5705D01*
G01Y4971D02*
X719696Y5305D01*
X720029Y5571D01*
X720496Y5705D01*
X720963Y5571D01*
X721296Y5305D01*
X721496Y4971D01*
Y3038D01*
G01Y4971D02*
X721696Y5305D01*
X722029Y5571D01*
X722496Y5705D01*
X722963Y5571D01*
X723296Y5305D01*
X723496Y4905D01*
Y3038D01*
G01X726096Y5705D02*
Y3038D01*
G01Y6771D02*
X725963Y6838D01*
Y6971D01*
X726096Y7038D01*
X726229Y6971D01*
Y6838D01*
X726096Y6771D01*
G01X730696Y3038D02*
Y7038D01*
G01X734296Y3505D02*
X734629Y3238D01*
X735096Y3038D01*
X735496D01*
X735896Y3171D01*
X736163Y3371D01*
X736296Y3638D01*
X736229Y4038D01*
X735963Y4238D01*
X734763Y4638D01*
X734496Y5105D01*
X734629Y5438D01*
X734896Y5638D01*
X735296Y5705D01*
X735696Y5638D01*
X736096Y5438D01*
G01X483800Y137224D02*
G03X493878I5039J0D01*
G01X534010Y189308D02*
X536010Y191308D01*
X532010D01*
X534010Y189308D01*
X534069Y200535D01*
G01X487899Y195571D02*
Y185871D01*
X482899Y190871D01*
X492899D01*
X487899Y185871D01*
G01X493563Y164744D02*
G03X484115I-4724J0D01*
G01D02*
G03X493563I4724J0D01*
G01X493878Y137224D02*
G03X483800I-5039J0D01*
G01X542194Y203859D02*
X541661Y204192D01*
X541061Y204392D01*
X540527D01*
X539994Y204192D01*
X539594Y203859D01*
X539394Y203392D01*
X539527Y202925D01*
X539861Y202525D01*
X540461Y202259D01*
X541261Y202125D01*
X541727Y201859D01*
X541927Y201392D01*
X541794Y200925D01*
X541461Y200592D01*
X540994Y200392D01*
X540527D01*
X540061Y200525D01*
X539661Y200859D01*
G01X536194Y204392D02*
Y200392D01*
G01X531594Y201725D02*
Y204392D01*
G01Y200659D02*
X531727Y200592D01*
Y200459D01*
X531594Y200392D01*
X531461Y200459D01*
Y200592D01*
X531594Y200659D01*
G01X526994Y200392D02*
Y204392D01*
G01X527927Y201725D02*
X526061D01*
G01X493622Y245605D02*
G03I-4291J0D01*
G01Y698924D02*
G03I-4291J0D01*
G01X601103Y3038D02*
Y7038D01*
X602703D01*
X603236Y6838D01*
X603636Y6371D01*
X603769Y5838D01*
X603636Y5305D01*
X603303Y4905D01*
X602703Y4705D01*
X601103D01*
G01X606103Y3038D02*
Y5705D01*
G01Y5171D02*
X606436Y5438D01*
X606769Y5638D01*
X607236Y5705D01*
X607569Y5638D01*
X607969Y5438D01*
G01X610636Y4838D02*
X612769D01*
X612569Y5305D01*
X612236Y5571D01*
X611769Y5705D01*
X611303Y5638D01*
X610903Y5438D01*
X610636Y4971D01*
X610503Y4571D01*
Y4171D01*
X610636Y3771D01*
X610969Y3371D01*
X611369Y3105D01*
X611836Y3038D01*
X612303Y3171D01*
X612769Y3571D01*
G01X615236Y3505D02*
X615569Y3238D01*
X616036Y3038D01*
X616436D01*
X616836Y3171D01*
X617103Y3371D01*
X617236Y3638D01*
X617169Y4038D01*
X616903Y4238D01*
X615703Y4638D01*
X615436Y5105D01*
X615569Y5438D01*
X615836Y5638D01*
X616236Y5705D01*
X616636Y5638D01*
X617036Y5438D01*
G01X619836Y3505D02*
X620169Y3238D01*
X620636Y3038D01*
X621036D01*
X621436Y3171D01*
X621703Y3371D01*
X621836Y3638D01*
X621769Y4038D01*
X621503Y4238D01*
X620303Y4638D01*
X620036Y5105D01*
X620169Y5438D01*
X620436Y5638D01*
X620836Y5705D01*
X621236Y5638D01*
X621636Y5438D01*
G01X624569Y4371D02*
X626303D01*
G01X629636Y3038D02*
Y6438D01*
X629769Y6771D01*
X630036Y6971D01*
X630436Y7038D01*
X630836Y6905D01*
X631036Y6571D01*
G01X630236Y5438D02*
X628903D01*
G01X634636Y5705D02*
Y3038D01*
G01Y6771D02*
X634503Y6838D01*
Y6971D01*
X634636Y7038D01*
X634769Y6971D01*
Y6838D01*
X634636Y6771D01*
G01X639236Y7038D02*
Y3038D01*
G01X638303Y5705D02*
X640169D01*
G01X647103Y3038D02*
Y7038D01*
X648703D01*
X649236Y6838D01*
X649636Y6371D01*
X649769Y5838D01*
X649636Y5305D01*
X649303Y4905D01*
X648703Y4705D01*
X647103D01*
G01X653036Y7038D02*
Y3038D01*
G01X651503Y7038D02*
X654569D01*
G01X656236Y3038D02*
Y7038D01*
G01X659036D02*
Y3038D01*
G01Y5038D02*
X656236D01*
G01X665703Y3038D02*
Y7038D01*
G01X667836Y5705D02*
X665703Y4171D01*
G01X666569Y4771D02*
X667969Y3038D01*
G01X670436Y4838D02*
X672569D01*
X672369Y5305D01*
X672036Y5571D01*
X671569Y5705D01*
X671103Y5638D01*
X670703Y5438D01*
X670436Y4971D01*
X670303Y4571D01*
Y4171D01*
X670436Y3771D01*
X670769Y3371D01*
X671169Y3105D01*
X671636Y3038D01*
X672103Y3171D01*
X672569Y3571D01*
G01X675036Y4838D02*
X677169D01*
X676969Y5305D01*
X676636Y5571D01*
X676169Y5705D01*
X675703Y5638D01*
X675303Y5438D01*
X675036Y4971D01*
X674903Y4571D01*
Y4171D01*
X675036Y3771D01*
X675369Y3371D01*
X675769Y3105D01*
X676236Y3038D01*
X676703Y3171D01*
X677169Y3571D01*
G01X679436Y1705D02*
Y5705D01*
G01Y5105D02*
X679769Y5438D01*
X680103Y5638D01*
X680636Y5705D01*
X681103Y5638D01*
X681569Y5305D01*
X681769Y4838D01*
X681836Y4371D01*
X681769Y3905D01*
X681569Y3438D01*
X681169Y3171D01*
X680636Y3038D01*
X680169Y3105D01*
X679703Y3305D01*
X679436Y3571D01*
G01X688703Y3038D02*
Y7038D01*
G01Y5105D02*
X689036Y5438D01*
X689369Y5638D01*
X689903Y5705D01*
X690303Y5638D01*
X690769Y5371D01*
X690969Y4971D01*
Y3038D01*
G01X694436D02*
X694036Y3105D01*
X693636Y3371D01*
X693369Y3838D01*
X693236Y4371D01*
X693369Y4905D01*
X693636Y5371D01*
X694036Y5638D01*
X694436Y5705D01*
X694836Y5638D01*
X695236Y5371D01*
X695503Y4905D01*
X695569Y4371D01*
X695503Y3838D01*
X695236Y3371D01*
X694836Y3105D01*
X694436Y3038D01*
G01X699036D02*
Y7038D01*
G01X702636Y4838D02*
X704769D01*
X704569Y5305D01*
X704236Y5571D01*
X703769Y5705D01*
X703303Y5638D01*
X702903Y5438D01*
X702636Y4971D01*
X702503Y4571D01*
Y4171D01*
X702636Y3771D01*
X702969Y3371D01*
X703369Y3105D01*
X703836Y3038D01*
X704303Y3171D01*
X704769Y3571D01*
G01X711836Y3505D02*
X712169Y3238D01*
X712636Y3038D01*
X713036D01*
X713436Y3171D01*
X713703Y3371D01*
X713836Y3638D01*
X713769Y4038D01*
X713503Y4238D01*
X712303Y4638D01*
X712036Y5105D01*
X712169Y5438D01*
X712436Y5638D01*
X712836Y5705D01*
X713236Y5638D01*
X713636Y5438D01*
G01X717436Y5705D02*
Y3038D01*
G01Y6771D02*
X717303Y6838D01*
Y6971D01*
X717436Y7038D01*
X717569Y6971D01*
Y6838D01*
X717436Y6771D01*
G01X721036Y5705D02*
X723036D01*
X721036Y3038D01*
X723036D01*
G01X725636Y4838D02*
X727769D01*
X727569Y5305D01*
X727236Y5571D01*
X726769Y5705D01*
X726303Y5638D01*
X725903Y5438D01*
X725636Y4971D01*
X725503Y4571D01*
Y4171D01*
X725636Y3771D01*
X725969Y3371D01*
X726369Y3105D01*
X726836Y3038D01*
X727303Y3171D01*
X727769Y3571D01*
G01X735836Y7038D02*
Y3038D01*
G01X734903Y5705D02*
X736769D01*
G01X740436Y3038D02*
X740036Y3105D01*
X739636Y3371D01*
X739369Y3838D01*
X739236Y4371D01*
X739369Y4905D01*
X739636Y5371D01*
X740036Y5638D01*
X740436Y5705D01*
X740836Y5638D01*
X741236Y5371D01*
X741503Y4905D01*
X741569Y4371D01*
X741503Y3838D01*
X741236Y3371D01*
X740836Y3105D01*
X740436Y3038D01*
G01X745036D02*
Y7038D01*
G01X748636Y4838D02*
X750769D01*
X750569Y5305D01*
X750236Y5571D01*
X749769Y5705D01*
X749303Y5638D01*
X748903Y5438D01*
X748636Y4971D01*
X748503Y4571D01*
Y4171D01*
X748636Y3771D01*
X748969Y3371D01*
X749369Y3105D01*
X749836Y3038D01*
X750303Y3171D01*
X750769Y3571D01*
G01X753303Y3038D02*
Y5705D01*
G01Y5171D02*
X753636Y5438D01*
X753969Y5638D01*
X754436Y5705D01*
X754769Y5638D01*
X755169Y5438D01*
G01X760036Y3038D02*
Y5705D01*
G01Y5238D02*
X759769Y5505D01*
X759369Y5638D01*
X758903Y5705D01*
X758436Y5571D01*
X758036Y5305D01*
X757769Y4905D01*
X757636Y4371D01*
X757769Y3838D01*
X758036Y3438D01*
X758436Y3171D01*
X758903Y3038D01*
X759369Y3105D01*
X759769Y3305D01*
X760036Y3571D01*
G01X762303Y3038D02*
Y5705D01*
G01Y5038D02*
X762569Y5371D01*
X762969Y5638D01*
X763503Y5705D01*
X763969Y5638D01*
X764369Y5371D01*
X764569Y4905D01*
Y3038D01*
G01X769103Y5371D02*
X768636Y5638D01*
X768236Y5705D01*
X767703Y5571D01*
X767303Y5305D01*
X767036Y4838D01*
X766969Y4371D01*
X767036Y3905D01*
X767303Y3505D01*
X767703Y3171D01*
X768236Y3038D01*
X768703Y3171D01*
X769103Y3438D01*
G01X771636Y4838D02*
X773769D01*
X773569Y5305D01*
X773236Y5571D01*
X772769Y5705D01*
X772303Y5638D01*
X771903Y5438D01*
X771636Y4971D01*
X771503Y4571D01*
Y4171D01*
X771636Y3771D01*
X771969Y3371D01*
X772369Y3105D01*
X772836Y3038D01*
X773303Y3171D01*
X773769Y3571D01*
G01X781103Y4371D02*
X782703D01*
G01X781836Y5238D02*
Y3505D01*
G01X785236Y2905D02*
X787636Y7038D01*
G01X790169Y4371D02*
X791903D01*
G01X794369Y6371D02*
X794769Y6771D01*
X795236Y6971D01*
X795769Y7038D01*
X796436Y6905D01*
X796903Y6571D01*
X797036Y6171D01*
X796969Y5771D01*
X796703Y5438D01*
X795369Y4771D01*
X794769Y4305D01*
X794369Y3638D01*
X794236Y3038D01*
X797036D01*
G01X798236D02*
Y5705D01*
G01Y4971D02*
X798436Y5305D01*
X798769Y5571D01*
X799236Y5705D01*
X799703Y5571D01*
X800036Y5305D01*
X800236Y4971D01*
Y3038D01*
G01Y4971D02*
X800436Y5305D01*
X800769Y5571D01*
X801236Y5705D01*
X801703Y5571D01*
X802036Y5305D01*
X802236Y4905D01*
Y3038D01*
G01X804836Y5705D02*
Y3038D01*
G01Y6771D02*
X804703Y6838D01*
Y6971D01*
X804836Y7038D01*
X804969Y6971D01*
Y6838D01*
X804836Y6771D01*
G01X809436Y3038D02*
Y7038D01*
G01X813036Y3505D02*
X813369Y3238D01*
X813836Y3038D01*
X814236D01*
X814636Y3171D01*
X814903Y3371D01*
X815036Y3638D01*
X814969Y4038D01*
X814703Y4238D01*
X813503Y4638D01*
X813236Y5105D01*
X813369Y5438D01*
X813636Y5638D01*
X814036Y5705D01*
X814436Y5638D01*
X814836Y5438D01*
G01X556299Y196850D02*
G03X560236Y200787I0J3937D01*
G01X564173Y188976D02*
G03X568110I1968J0D01*
G01Y723480D02*
Y188976D01*
G01X560236Y316929D02*
Y200787D01*
G01X568110Y316929D02*
G03X560236I-3937J0D01*
G01X568110D02*
G03X560236I-3937J0D01*
G01Y690803D02*
Y347638D01*
G01D02*
G03X568110I3937J0D01*
G01X560236D02*
G03X568110I3937J0D01*
G01X560236Y721512D02*
Y723481D01*
G01X561484Y728764D02*
G03X560236Y723482I10563J-5284D01*
G01X568526Y725241D02*
G03X568110Y723480I3521J-1761D01*
G01X560236Y721512D02*
G03X568110I3937J0D01*
G01Y690803D02*
G03X560236I-3937J0D01*
G01Y721512D02*
G03X568110I3937J0D01*
G01Y690803D02*
G03X560236I-3937J0D01*
G01X576143Y758082D02*
G03X572622Y763780I-3521J1761D01*
G01X576143Y758082D02*
X561483Y728762D01*
G01X586707Y761603D02*
X568526Y725241D01*
G01X590228Y763780D02*
G03X586707Y761603I1J-3937D01*
G01X903079Y763780D02*
X590228D01*
G01X654371Y129624D02*
Y17224D01*
X605471D01*
Y129624D01*
X654371D01*
G01X633780Y7274D02*
Y16974D01*
X636921Y12874D01*
X630921D01*
X633780Y16974D01*
G01X634252Y57874D02*
G03X625591I-4331J0D01*
G01D02*
G03X634252I4331J0D01*
G01X658661Y180000D02*
G03X646850I-5905J0D01*
G01D02*
G03X658661I5906J0D01*
G01X619094Y433071D02*
G03X605315I-6889J0D01*
G01D02*
G03X619094I6890J0D01*
G01Y740157D02*
G03X605315I-6889J0D01*
G01D02*
G03X619094I6890J0D01*
G01X733111Y129624D02*
Y17224D01*
X684211D01*
Y129624D01*
X733111D01*
G01X712520Y7274D02*
Y16974D01*
X715661Y12874D01*
X709661D01*
X712520Y16974D01*
G01X712992Y57874D02*
G03X704331I-4331J0D01*
G01D02*
G03X712992I4330J0D01*
G01X859449Y332598D02*
G03X871260I5905J0D01*
G01D02*
G03X859449I-5906J0D01*
G01X921260Y0D02*
G03X925197Y3937I0J3937D01*
G01X883858Y59055D02*
G03X868110I-7874J0D01*
G01D02*
G03X883858I7874J0D01*
G01X925197Y3937D02*
Y723480D01*
G01X882874Y433071D02*
G03X869094I-6890J0D01*
G01D02*
G03X882874I6890J0D01*
G01X925197Y723480D02*
G03X924781Y725241I-3937J0D01*
G01X882874Y740157D02*
G03X869094I-6890J0D01*
G01D02*
G03X882874I6890J0D01*
G01X906600Y761603D02*
G03X903079Y763780I-3522J-1760D01*
G01X924781Y725241D02*
X906600Y761603D01*
G54D19*
X102700Y507100D03*
X101800Y493000D03*
X123500Y613100D03*
X141971Y624700D03*
X105600Y597000D03*
X105400Y601300D03*
X104600Y609900D03*
X105600Y605900D03*
X104600Y614000D03*
X104500Y618800D03*
X116200Y611600D03*
X116023Y607423D03*
X119400Y614100D03*
X116400Y616900D03*
X129903Y634500D03*
X176000Y460200D03*
X183300Y493100D03*
X205447Y487762D03*
X182874Y523590D03*
X165900Y524100D03*
X196200Y482600D03*
X195379Y510158D03*
X194490Y645390D03*
X151550Y629800D03*
X146800Y629900D03*
X204150Y645180D03*
X199600Y650100D03*
X192960Y628510D03*
X187900Y628500D03*
X150849Y710215D03*
X254500Y509600D03*
X228700Y490717D03*
X230700Y486658D03*
X249640Y495080D03*
X234700Y490900D03*
X254905Y555761D03*
X286797Y516522D03*
X292100Y516000D03*
X297400Y517981D03*
X278400Y463300D03*
X333800Y534830D03*
X329840Y572710D03*
X325475Y572818D03*
X298000Y561000D03*
X328580Y568120D03*
X320954Y572631D03*
X337346Y545100D03*
X308200Y593153D03*
X325300Y648700D03*
X330400Y644300D03*
X327250Y701500D03*
X316000Y671850D03*
X390229Y508189D03*
X373800Y503000D03*
X378267Y496100D03*
X344163Y553395D03*
X364964Y588771D03*
X380387Y685261D03*
X392500Y673500D03*
X564500Y64100D03*
X586155Y393023D03*
X665500Y201900D03*
X657500Y281500D03*
X648000Y281300D03*
X768579Y203964D03*
X735300Y401957D03*
X1129450Y758550D03*
G54D28*
X421653Y126378D03*
X435827D03*
X450000D03*
X464173D03*
X428740Y121654D03*
X442913D03*
X457086D03*
X471260D03*
X421653Y130709D03*
X428740Y125985D03*
X435827Y130709D03*
X442913Y125985D03*
X450000Y130709D03*
X457086Y125985D03*
X464173Y130709D03*
X471260Y125985D03*
X428740Y131496D03*
X442913D03*
X457086D03*
X471260D03*
X421653Y183071D03*
X435827D03*
X450000D03*
X464173D03*
X421653Y136221D03*
X435827D03*
X450000D03*
X464173D03*
X421653Y140551D03*
X428740Y135827D03*
X435827Y140551D03*
X442913Y135827D03*
X450000Y140551D03*
X457086Y135827D03*
X464173Y140551D03*
X471260Y135827D03*
X421653Y144882D03*
X428740Y140158D03*
X435827Y144882D03*
X442913Y140158D03*
X450000Y144882D03*
X457086Y140158D03*
X464173Y144882D03*
X471260Y140158D03*
X421653Y150394D03*
X428740Y145670D03*
X435827Y150394D03*
X442913Y145670D03*
X450000Y150394D03*
X457086Y145670D03*
X464173Y150394D03*
X471260Y145670D03*
X421653Y154725D03*
X428740Y150000D03*
X435827Y154725D03*
X442913Y150000D03*
X450000Y154725D03*
X457086Y150000D03*
X464173Y154725D03*
X471260Y150000D03*
X421653Y159055D03*
X428740Y154331D03*
X435827Y159055D03*
X442913Y154331D03*
X450000Y159055D03*
X457086Y154331D03*
X464173Y159055D03*
X471260Y154331D03*
X421653Y164567D03*
X428740Y159843D03*
X435827Y164567D03*
X442913Y159843D03*
X450000Y164567D03*
X457086Y159843D03*
X464173Y164567D03*
X471260Y159843D03*
X421653Y168898D03*
X428740Y164173D03*
X435827Y168898D03*
X442913Y164173D03*
X450000Y168898D03*
X457086Y164173D03*
X464173Y168898D03*
X471260Y164173D03*
X421653Y173229D03*
X428740Y168504D03*
X435827Y173229D03*
X442913Y168504D03*
X450000Y173229D03*
X457086Y168504D03*
X464173Y173229D03*
X471260Y168504D03*
X421653Y178740D03*
X428740Y174016D03*
X435827Y178740D03*
X442913Y174016D03*
X450000Y178740D03*
X457086Y174016D03*
X464173Y178740D03*
X471260Y174016D03*
X506693Y126378D03*
X520866D03*
X535039D03*
X513779Y121654D03*
X527953D03*
X506693Y130709D03*
X513779Y125985D03*
X520866Y130709D03*
X527953Y125985D03*
X535039Y130709D03*
X513779Y131496D03*
X527953D03*
X506693Y183071D03*
X520866D03*
X535039D03*
X506693Y136221D03*
X520866D03*
X535039D03*
X506693Y140551D03*
X513779Y135827D03*
X520866Y140551D03*
X527953Y135827D03*
X535039Y140551D03*
X506693Y144882D03*
X513779Y140158D03*
X520866Y144882D03*
X527953Y140158D03*
X535039Y144882D03*
X506693Y150394D03*
X513779Y145670D03*
X520866Y150394D03*
X527953Y145670D03*
X535039Y150394D03*
X506693Y154725D03*
X513779Y150000D03*
X520866Y154725D03*
X527953Y150000D03*
X535039Y154725D03*
X506693Y159055D03*
X513779Y154331D03*
X520866Y159055D03*
X527953Y154331D03*
X535039Y159055D03*
X506693Y164567D03*
X513779Y159843D03*
X520866Y164567D03*
X527953Y159843D03*
X535039Y164567D03*
X506693Y168898D03*
X513779Y164173D03*
X520866Y168898D03*
X527953Y164173D03*
X535039Y168898D03*
X506693Y173229D03*
X513779Y168504D03*
X520866Y173229D03*
X527953Y168504D03*
X535039Y173229D03*
X506693Y178740D03*
X513779Y174016D03*
X520866Y178740D03*
X527953Y174016D03*
X535039Y178740D03*
X549212Y126378D03*
X542126Y121654D03*
X556299D03*
X542126Y125985D03*
X549212Y130709D03*
X556299Y125985D03*
X542126Y131496D03*
X556299D03*
X549212Y183071D03*
Y136221D03*
X542126Y135827D03*
X549212Y140551D03*
X556299Y135827D03*
X542126Y140158D03*
X549212Y144882D03*
X556299Y140158D03*
X542126Y145670D03*
X549212Y150394D03*
X556299Y145670D03*
X542126Y150000D03*
X549212Y154725D03*
X556299Y150000D03*
X542126Y154331D03*
X549212Y159055D03*
X556299Y154331D03*
X542126Y159843D03*
X549212Y164567D03*
X556299Y159843D03*
X542126Y164173D03*
X549212Y168898D03*
X556299Y164173D03*
X542126Y168504D03*
X549212Y173229D03*
X556299Y168504D03*
X542126Y174016D03*
X549212Y178740D03*
X556299Y174016D03*
X1129450Y702350D03*
G54D29*
X488838Y137225D03*
X1129450Y252750D03*
M02*
